FILE_TYPE = MACRO_DRAWING;
SET COLOR_WIRE YELLOW;
SET COLOR_PROP MONO;
SET COLOR_DOT WHITE;
SET COLOR_ARC YELLOW;
SET COLOR_BODY GREEN;
SET COLOR_NOTE MONO;
SET PROP_DISPLAY VALUE;
SET PAGE_NUMBER P149;
FORCEADD CAP..1
(550 5400);
FORCEPROP 1 LAST LOCATION C25W30
J 0
(600 5525);
DISPLAY 0.638298 (600 5525);
PAINT SKYBLUE (600 5525);
FORCEPROP 1 LAST VALUE 4.7UF
J 0
(600 5475);
DISPLAY 0.638298 (600 5475);
PAINT SKYBLUE (600 5475);
FORCEPROP 1 LAST PART_NUMBER E15431-003
J 0
(600 5225);
DISPLAY 0.638298 (600 5225);
PAINT BLUE (600 5225);
FORCEPROP 1 LAST PACK_TYPE 0603
J 0
(600 5275);
DISPLAY 0.638298 (600 5275);
PAINT SKYBLUE (600 5275);
FORCEPROP 1 LAST VOLTAGE 6.3V
J 0
(600 5425);
DISPLAY 0.638298 (600 5425);
PAINT SKYBLUE (600 5425);
FORCEPROP 1 LAST TOLERANCE 10%
J 0
(600 5375);
DISPLAY 0.638298 (600 5375);
PAINT SKYBLUE (600 5375);
FORCEPROP 1 LAST MATERIAL X6S
J 0
(600 5325);
DISPLAY 0.638298 (600 5325);
PAINT SKYBLUE (600 5325);
FORCEPROP 1 LAST PATH I1
J 0
(600 5550);
DISPLAY 0.978723 (600 5550);
PAINT WHITE (600 5550);
DISPLAY INVISIBLE (600 5550);
FORCEPROP 0 LAST CDS_SEC 1
J 0
(600 5575);
PAINT MONO (600 5575);
DISPLAY INVISIBLE (600 5575);
FORCEPROP 0 LAST $SEC 1
J 0
(600 5575);
PAINT MONO (600 5575);
DISPLAY INVISIBLE (600 5575);
FORCEPROP 0 LAST CDS_LOCATION C25W30
J 0
(600 5575);
PAINT MONO (600 5575);
DISPLAY INVISIBLE (600 5575);
FORCEPROP 1 LASTPIN (550 5500) $PN 1
J 0
(560 5480);
DISPLAY 0.787234 (560 5480);
PAINT ORANGE (560 5480);
DISPLAY INVISIBLE (560 5480);
FORCEPROP 1 LASTPIN (550 5300) $PN 2
J 0
(560 5280);
DISPLAY 0.787234 (560 5280);
PAINT ORANGE (560 5280);
DISPLAY INVISIBLE (560 5280);
FORCEPROP 2 LAST CDS_LIB mstr_discrete
J 0
(550 5400);
PAINT MONO (550 5400);
DISPLAY INVISIBLE (550 5400);
FORCEADD CAP..1
(-650 2900);
FORCEPROP 1 LAST PACK_TYPE 0402
J 0
(-600 2700);
DISPLAY 0.617021 (-600 2700);
PAINT SKYBLUE (-600 2700);
FORCEPROP 1 LAST MATERIAL X6S
J 0
(-600 2800);
DISPLAY 0.617021 (-600 2800);
PAINT SKYBLUE (-600 2800);
FORCEPROP 1 LAST TOLERANCE 10%
J 0
(-600 2850);
DISPLAY 0.617021 (-600 2850);
PAINT SKYBLUE (-600 2850);
FORCEPROP 1 LAST VOLTAGE 16V
J 0
(-600 2900);
DISPLAY 0.617021 (-600 2900);
PAINT SKYBLUE (-600 2900);
FORCEPROP 1 LAST VALUE 1.0UF
J 0
(-600 2950);
DISPLAY 0.617021 (-600 2950);
PAINT SKYBLUE (-600 2950);
FORCEPROP 1 LAST LOCATION C25W43
J 0
(-600 3000);
DISPLAY 0.617021 (-600 3000);
PAINT AQUA (-600 3000);
FORCEPROP 1 LAST PART_NUMBER D97712-011
J 0
(-600 2750);
DISPLAY 0.617021 (-600 2750);
PAINT BLUE (-600 2750);
FORCEPROP 0 LAST ROOM PROC_SIDEBAND
J 0
(-600 3100);
DISPLAY 1.021277 (-600 3100);
PAINT ORANGE (-600 3100);
DISPLAY INVISIBLE (-600 3100);
FORCEPROP 0 LAST BOM_COST PROC
J 0
(-600 3100);
DISPLAY 1.021277 (-600 3100);
PAINT ORANGE (-600 3100);
DISPLAY INVISIBLE (-600 3100);
FORCEPROP 1 LAST PATH I100
J 0
(-600 3050);
DISPLAY 0.978723 (-600 3050);
PAINT WHITE (-600 3050);
DISPLAY INVISIBLE (-600 3050);
FORCEPROP 2 LAST CDS_LIB mstr_discrete
J 0
(-650 2900);
PAINT MONO (-650 2900);
DISPLAY INVISIBLE (-650 2900);
FORCEPROP 1 LASTPIN (-650 2800) $PN 2
J 0
(-640 2780);
DISPLAY 0.787234 (-640 2780);
PAINT ORANGE (-640 2780);
DISPLAY INVISIBLE (-640 2780);
FORCEPROP 1 LASTPIN (-650 3000) $PN 1
J 0
(-640 2980);
DISPLAY 0.787234 (-640 2980);
PAINT ORANGE (-640 2980);
DISPLAY INVISIBLE (-640 2980);
FORCEADD CAP..1
(-350 2900);
FORCEPROP 1 LAST PART_NUMBER D97712-011
J 0
(-300 2750);
DISPLAY 0.617021 (-300 2750);
PAINT BLUE (-300 2750);
FORCEPROP 1 LAST VALUE 1.0UF
J 0
(-300 2950);
DISPLAY 0.617021 (-300 2950);
PAINT SKYBLUE (-300 2950);
FORCEPROP 1 LAST TOLERANCE 10%
J 0
(-300 2850);
DISPLAY 0.617021 (-300 2850);
PAINT SKYBLUE (-300 2850);
FORCEPROP 1 LAST VOLTAGE 16V
J 0
(-300 2900);
DISPLAY 0.617021 (-300 2900);
PAINT SKYBLUE (-300 2900);
FORCEPROP 1 LAST MATERIAL X6S
J 0
(-300 2800);
DISPLAY 0.617021 (-300 2800);
PAINT SKYBLUE (-300 2800);
FORCEPROP 1 LAST PACK_TYPE 0402
J 0
(-300 2700);
DISPLAY 0.617021 (-300 2700);
PAINT SKYBLUE (-300 2700);
FORCEPROP 1 LAST LOCATION C25W44
J 0
(-300 3000);
DISPLAY 0.617021 (-300 3000);
PAINT AQUA (-300 3000);
FORCEPROP 0 LAST BOM_COST PROC
J 0
(-300 3100);
DISPLAY 1.021277 (-300 3100);
PAINT ORANGE (-300 3100);
DISPLAY INVISIBLE (-300 3100);
FORCEPROP 0 LAST ROOM PROC_SIDEBAND
J 0
(-300 3100);
DISPLAY 1.021277 (-300 3100);
PAINT ORANGE (-300 3100);
DISPLAY INVISIBLE (-300 3100);
FORCEPROP 1 LAST PATH I101
J 0
(-300 3050);
DISPLAY 0.978723 (-300 3050);
PAINT WHITE (-300 3050);
DISPLAY INVISIBLE (-300 3050);
FORCEPROP 2 LAST CDS_LIB mstr_discrete
J 0
(-350 2900);
PAINT MONO (-350 2900);
DISPLAY INVISIBLE (-350 2900);
FORCEPROP 1 LASTPIN (-350 2800) $PN 2
J 0
(-340 2780);
DISPLAY 0.787234 (-340 2780);
PAINT ORANGE (-340 2780);
DISPLAY INVISIBLE (-340 2780);
FORCEPROP 1 LASTPIN (-350 3000) $PN 1
J 0
(-340 2980);
DISPLAY 0.787234 (-340 2980);
PAINT ORANGE (-340 2980);
DISPLAY INVISIBLE (-340 2980);
FORCEADD CAP..1
(-675 4100);
FORCEPROP 1 LAST PACK_TYPE 0402
J 0
(-625 3900);
DISPLAY 0.617021 (-625 3900);
PAINT SKYBLUE (-625 3900);
FORCEPROP 1 LAST MATERIAL X6S
J 0
(-625 4000);
DISPLAY 0.617021 (-625 4000);
PAINT SKYBLUE (-625 4000);
FORCEPROP 1 LAST LOCATION C25W33
J 0
(-625 4200);
DISPLAY 0.617021 (-625 4200);
PAINT AQUA (-625 4200);
FORCEPROP 1 LAST VALUE 1.0UF
J 0
(-625 4150);
DISPLAY 0.617021 (-625 4150);
PAINT SKYBLUE (-625 4150);
FORCEPROP 1 LAST VOLTAGE 16V
J 0
(-625 4100);
DISPLAY 0.617021 (-625 4100);
PAINT SKYBLUE (-625 4100);
FORCEPROP 1 LAST TOLERANCE 10%
J 0
(-625 4050);
DISPLAY 0.617021 (-625 4050);
PAINT SKYBLUE (-625 4050);
FORCEPROP 1 LAST PART_NUMBER D97712-011
J 0
(-625 3950);
DISPLAY 0.617021 (-625 3950);
PAINT BLUE (-625 3950);
FORCEPROP 0 LAST ROOM PROC_SIDEBAND
J 0
(-625 4300);
DISPLAY 1.021277 (-625 4300);
PAINT ORANGE (-625 4300);
DISPLAY INVISIBLE (-625 4300);
FORCEPROP 0 LAST BOM_COST PROC
J 0
(-625 4300);
DISPLAY 1.021277 (-625 4300);
PAINT ORANGE (-625 4300);
DISPLAY INVISIBLE (-625 4300);
FORCEPROP 1 LAST PATH I102
J 0
(-625 4250);
DISPLAY 0.978723 (-625 4250);
PAINT WHITE (-625 4250);
DISPLAY INVISIBLE (-625 4250);
FORCEPROP 2 LAST CDS_LIB mstr_discrete
J 0
(-675 4100);
PAINT MONO (-675 4100);
DISPLAY INVISIBLE (-675 4100);
FORCEPROP 1 LASTPIN (-675 4000) $PN 2
J 0
(-665 3980);
DISPLAY 0.787234 (-665 3980);
PAINT ORANGE (-665 3980);
DISPLAY INVISIBLE (-665 3980);
FORCEPROP 1 LASTPIN (-675 4200) $PN 1
J 0
(-665 4180);
DISPLAY 0.787234 (-665 4180);
PAINT ORANGE (-665 4180);
DISPLAY INVISIBLE (-665 4180);
FORCEADD CAP..1
(-2250 5400);
FORCEPROP 1 LAST VOLTAGE 16V
J 0
(-2200 5400);
DISPLAY 0.617021 (-2200 5400);
PAINT SKYBLUE (-2200 5400);
FORCEPROP 1 LAST VALUE 1.0UF
J 0
(-2200 5450);
DISPLAY 0.617021 (-2200 5450);
PAINT SKYBLUE (-2200 5450);
FORCEPROP 1 LAST LOCATION C25W23
J 0
(-2200 5500);
DISPLAY 0.617021 (-2200 5500);
PAINT AQUA (-2200 5500);
FORCEPROP 1 LAST PACK_TYPE 0402
J 0
(-2200 5200);
DISPLAY 0.617021 (-2200 5200);
PAINT SKYBLUE (-2200 5200);
FORCEPROP 1 LAST TOLERANCE 10%
J 0
(-2200 5350);
DISPLAY 0.617021 (-2200 5350);
PAINT SKYBLUE (-2200 5350);
FORCEPROP 1 LAST PART_NUMBER D97712-011
J 0
(-2200 5250);
DISPLAY 0.617021 (-2200 5250);
PAINT BLUE (-2200 5250);
FORCEPROP 1 LAST MATERIAL X6S
J 0
(-2200 5300);
DISPLAY 0.617021 (-2200 5300);
PAINT SKYBLUE (-2200 5300);
FORCEPROP 0 LAST ROOM PROC_SIDEBAND
J 0
(-2200 5600);
DISPLAY 1.021277 (-2200 5600);
PAINT ORANGE (-2200 5600);
DISPLAY INVISIBLE (-2200 5600);
FORCEPROP 0 LAST BOM_COST PROC
J 0
(-2200 5600);
DISPLAY 1.021277 (-2200 5600);
PAINT ORANGE (-2200 5600);
DISPLAY INVISIBLE (-2200 5600);
FORCEPROP 1 LAST PATH I103
J 0
(-2200 5550);
DISPLAY 0.978723 (-2200 5550);
PAINT WHITE (-2200 5550);
DISPLAY INVISIBLE (-2200 5550);
FORCEPROP 2 LAST CDS_LIB mstr_discrete
J 0
(-2250 5400);
PAINT MONO (-2250 5400);
DISPLAY INVISIBLE (-2250 5400);
FORCEPROP 1 LASTPIN (-2250 5300) $PN 2
J 0
(-2240 5280);
DISPLAY 0.787234 (-2240 5280);
PAINT ORANGE (-2240 5280);
DISPLAY INVISIBLE (-2240 5280);
FORCEPROP 1 LASTPIN (-2250 5500) $PN 1
J 0
(-2240 5480);
DISPLAY 0.787234 (-2240 5480);
PAINT ORANGE (-2240 5480);
DISPLAY INVISIBLE (-2240 5480);
FORCEADD CAP..1
(-1850 5400);
FORCEPROP 1 LAST TOLERANCE 10%
J 0
(-1800 5350);
DISPLAY 0.617021 (-1800 5350);
PAINT SKYBLUE (-1800 5350);
FORCEPROP 1 LAST LOCATION C25W24
J 0
(-1800 5500);
DISPLAY 0.617021 (-1800 5500);
PAINT AQUA (-1800 5500);
FORCEPROP 1 LAST PART_NUMBER D97712-011
J 0
(-1800 5250);
DISPLAY 0.617021 (-1800 5250);
PAINT BLUE (-1800 5250);
FORCEPROP 1 LAST VALUE 1.0UF
J 0
(-1800 5450);
DISPLAY 0.617021 (-1800 5450);
PAINT SKYBLUE (-1800 5450);
FORCEPROP 1 LAST VOLTAGE 16V
J 0
(-1800 5400);
DISPLAY 0.617021 (-1800 5400);
PAINT SKYBLUE (-1800 5400);
FORCEPROP 1 LAST MATERIAL X6S
J 0
(-1800 5300);
DISPLAY 0.617021 (-1800 5300);
PAINT SKYBLUE (-1800 5300);
FORCEPROP 1 LAST PACK_TYPE 0402
J 0
(-1800 5200);
DISPLAY 0.617021 (-1800 5200);
PAINT SKYBLUE (-1800 5200);
FORCEPROP 0 LAST BOM_COST PROC
J 0
(-1800 5600);
DISPLAY 1.021277 (-1800 5600);
PAINT ORANGE (-1800 5600);
DISPLAY INVISIBLE (-1800 5600);
FORCEPROP 0 LAST ROOM PROC_SIDEBAND
J 0
(-1800 5600);
DISPLAY 1.021277 (-1800 5600);
PAINT ORANGE (-1800 5600);
DISPLAY INVISIBLE (-1800 5600);
FORCEPROP 1 LAST PATH I104
J 0
(-1800 5550);
DISPLAY 0.978723 (-1800 5550);
PAINT WHITE (-1800 5550);
DISPLAY INVISIBLE (-1800 5550);
FORCEPROP 2 LAST CDS_LIB mstr_discrete
J 0
(-1850 5400);
PAINT MONO (-1850 5400);
DISPLAY INVISIBLE (-1850 5400);
FORCEPROP 1 LASTPIN (-1850 5300) $PN 2
J 0
(-1840 5280);
DISPLAY 0.787234 (-1840 5280);
PAINT ORANGE (-1840 5280);
DISPLAY INVISIBLE (-1840 5280);
FORCEPROP 1 LASTPIN (-1850 5500) $PN 1
J 0
(-1840 5480);
DISPLAY 0.787234 (-1840 5480);
PAINT ORANGE (-1840 5480);
DISPLAY INVISIBLE (-1840 5480);
FORCEADD CAP..1
(-1450 5400);
FORCEPROP 1 LAST PACK_TYPE 0402
J 0
(-1400 5200);
DISPLAY 0.617021 (-1400 5200);
PAINT SKYBLUE (-1400 5200);
FORCEPROP 1 LAST VOLTAGE 16V
J 0
(-1400 5400);
DISPLAY 0.617021 (-1400 5400);
PAINT SKYBLUE (-1400 5400);
FORCEPROP 1 LAST TOLERANCE 10%
J 0
(-1400 5350);
DISPLAY 0.617021 (-1400 5350);
PAINT SKYBLUE (-1400 5350);
FORCEPROP 1 LAST VALUE 1.0UF
J 0
(-1400 5450);
DISPLAY 0.617021 (-1400 5450);
PAINT SKYBLUE (-1400 5450);
FORCEPROP 1 LAST LOCATION C25W25
J 0
(-1400 5500);
DISPLAY 0.617021 (-1400 5500);
PAINT AQUA (-1400 5500);
FORCEPROP 1 LAST PART_NUMBER D97712-011
J 0
(-1400 5250);
DISPLAY 0.617021 (-1400 5250);
PAINT BLUE (-1400 5250);
FORCEPROP 1 LAST MATERIAL X6S
J 0
(-1400 5300);
DISPLAY 0.617021 (-1400 5300);
PAINT SKYBLUE (-1400 5300);
FORCEPROP 0 LAST ROOM PROC_SIDEBAND
J 0
(-1400 5600);
DISPLAY 1.021277 (-1400 5600);
PAINT ORANGE (-1400 5600);
DISPLAY INVISIBLE (-1400 5600);
FORCEPROP 0 LAST BOM_COST PROC
J 0
(-1400 5600);
DISPLAY 1.021277 (-1400 5600);
PAINT ORANGE (-1400 5600);
DISPLAY INVISIBLE (-1400 5600);
FORCEPROP 1 LAST PATH I105
J 0
(-1400 5550);
DISPLAY 0.978723 (-1400 5550);
PAINT WHITE (-1400 5550);
DISPLAY INVISIBLE (-1400 5550);
FORCEPROP 2 LAST CDS_LIB mstr_discrete
J 0
(-1450 5400);
PAINT MONO (-1450 5400);
DISPLAY INVISIBLE (-1450 5400);
FORCEPROP 1 LASTPIN (-1450 5300) $PN 2
J 0
(-1440 5280);
DISPLAY 0.787234 (-1440 5280);
PAINT ORANGE (-1440 5280);
DISPLAY INVISIBLE (-1440 5280);
FORCEPROP 1 LASTPIN (-1450 5500) $PN 1
J 0
(-1440 5480);
DISPLAY 0.787234 (-1440 5480);
PAINT ORANGE (-1440 5480);
DISPLAY INVISIBLE (-1440 5480);
FORCEADD CAP..1
(-1050 5400);
FORCEPROP 1 LAST LOCATION C25W26
J 0
(-1000 5500);
DISPLAY 0.617021 (-1000 5500);
PAINT AQUA (-1000 5500);
FORCEPROP 1 LAST TOLERANCE 10%
J 0
(-1000 5350);
DISPLAY 0.617021 (-1000 5350);
PAINT SKYBLUE (-1000 5350);
FORCEPROP 1 LAST MATERIAL X6S
J 0
(-1000 5300);
DISPLAY 0.617021 (-1000 5300);
PAINT SKYBLUE (-1000 5300);
FORCEPROP 1 LAST PART_NUMBER D97712-011
J 0
(-1000 5250);
DISPLAY 0.617021 (-1000 5250);
PAINT BLUE (-1000 5250);
FORCEPROP 1 LAST PACK_TYPE 0402
J 0
(-1000 5200);
DISPLAY 0.617021 (-1000 5200);
PAINT SKYBLUE (-1000 5200);
FORCEPROP 1 LAST VOLTAGE 16V
J 0
(-1000 5400);
DISPLAY 0.617021 (-1000 5400);
PAINT SKYBLUE (-1000 5400);
FORCEPROP 1 LAST VALUE 1.0UF
J 0
(-1000 5450);
DISPLAY 0.617021 (-1000 5450);
PAINT SKYBLUE (-1000 5450);
FORCEPROP 0 LAST BOM_COST PROC
J 0
(-1000 5600);
DISPLAY 1.021277 (-1000 5600);
PAINT ORANGE (-1000 5600);
DISPLAY INVISIBLE (-1000 5600);
FORCEPROP 0 LAST ROOM PROC_SIDEBAND
J 0
(-1000 5600);
DISPLAY 1.021277 (-1000 5600);
PAINT ORANGE (-1000 5600);
DISPLAY INVISIBLE (-1000 5600);
FORCEPROP 1 LAST PATH I106
J 0
(-1000 5550);
DISPLAY 0.978723 (-1000 5550);
PAINT WHITE (-1000 5550);
DISPLAY INVISIBLE (-1000 5550);
FORCEPROP 2 LAST CDS_LIB mstr_discrete
J 0
(-1050 5400);
PAINT MONO (-1050 5400);
DISPLAY INVISIBLE (-1050 5400);
FORCEPROP 1 LASTPIN (-1050 5300) $PN 2
J 0
(-1040 5280);
DISPLAY 0.787234 (-1040 5280);
PAINT ORANGE (-1040 5280);
DISPLAY INVISIBLE (-1040 5280);
FORCEPROP 1 LASTPIN (-1050 5500) $PN 1
J 0
(-1040 5480);
DISPLAY 0.787234 (-1040 5480);
PAINT ORANGE (-1040 5480);
DISPLAY INVISIBLE (-1040 5480);
FORCEADD CAP..1
(-650 5400);
FORCEPROP 1 LAST VOLTAGE 16V
J 0
(-600 5400);
DISPLAY 0.617021 (-600 5400);
PAINT SKYBLUE (-600 5400);
FORCEPROP 1 LAST TOLERANCE 10%
J 0
(-600 5350);
DISPLAY 0.617021 (-600 5350);
PAINT SKYBLUE (-600 5350);
FORCEPROP 1 LAST VALUE 1.0UF
J 0
(-600 5450);
DISPLAY 0.617021 (-600 5450);
PAINT SKYBLUE (-600 5450);
FORCEPROP 1 LAST LOCATION C25W27
J 0
(-600 5500);
DISPLAY 0.617021 (-600 5500);
PAINT AQUA (-600 5500);
FORCEPROP 1 LAST MATERIAL X6S
J 0
(-600 5300);
DISPLAY 0.617021 (-600 5300);
PAINT SKYBLUE (-600 5300);
FORCEPROP 1 LAST PART_NUMBER D97712-011
J 0
(-600 5250);
DISPLAY 0.617021 (-600 5250);
PAINT BLUE (-600 5250);
FORCEPROP 1 LAST PACK_TYPE 0402
J 0
(-600 5200);
DISPLAY 0.617021 (-600 5200);
PAINT SKYBLUE (-600 5200);
FORCEPROP 0 LAST ROOM PROC_SIDEBAND
J 0
(-600 5600);
DISPLAY 1.021277 (-600 5600);
PAINT ORANGE (-600 5600);
DISPLAY INVISIBLE (-600 5600);
FORCEPROP 0 LAST BOM_COST PROC
J 0
(-600 5600);
DISPLAY 1.021277 (-600 5600);
PAINT ORANGE (-600 5600);
DISPLAY INVISIBLE (-600 5600);
FORCEPROP 1 LAST PATH I107
J 0
(-600 5550);
DISPLAY 0.978723 (-600 5550);
PAINT WHITE (-600 5550);
DISPLAY INVISIBLE (-600 5550);
FORCEPROP 2 LAST CDS_LIB mstr_discrete
J 0
(-650 5400);
PAINT MONO (-650 5400);
DISPLAY INVISIBLE (-650 5400);
FORCEPROP 1 LASTPIN (-650 5300) $PN 2
J 0
(-640 5280);
DISPLAY 0.787234 (-640 5280);
PAINT ORANGE (-640 5280);
DISPLAY INVISIBLE (-640 5280);
FORCEPROP 1 LASTPIN (-650 5500) $PN 1
J 0
(-640 5480);
DISPLAY 0.787234 (-640 5480);
PAINT ORANGE (-640 5480);
DISPLAY INVISIBLE (-640 5480);
FORCEADD CAP..1
(-250 5400);
FORCEPROP 1 LAST LOCATION C25W28
J 0
(-200 5500);
DISPLAY 0.617021 (-200 5500);
PAINT AQUA (-200 5500);
FORCEPROP 1 LAST TOLERANCE 10%
J 0
(-200 5350);
DISPLAY 0.617021 (-200 5350);
PAINT SKYBLUE (-200 5350);
FORCEPROP 1 LAST VOLTAGE 16V
J 0
(-200 5400);
DISPLAY 0.617021 (-200 5400);
PAINT SKYBLUE (-200 5400);
FORCEPROP 1 LAST VALUE 1.0UF
J 0
(-200 5450);
DISPLAY 0.617021 (-200 5450);
PAINT SKYBLUE (-200 5450);
FORCEPROP 1 LAST MATERIAL X6S
J 0
(-200 5300);
DISPLAY 0.617021 (-200 5300);
PAINT SKYBLUE (-200 5300);
FORCEPROP 1 LAST PACK_TYPE 0402
J 0
(-200 5200);
DISPLAY 0.617021 (-200 5200);
PAINT SKYBLUE (-200 5200);
FORCEPROP 1 LAST PART_NUMBER D97712-011
J 0
(-200 5250);
DISPLAY 0.617021 (-200 5250);
PAINT BLUE (-200 5250);
FORCEPROP 0 LAST BOM_COST PROC
J 0
(-200 5600);
DISPLAY 1.021277 (-200 5600);
PAINT ORANGE (-200 5600);
DISPLAY INVISIBLE (-200 5600);
FORCEPROP 0 LAST ROOM PROC_SIDEBAND
J 0
(-200 5600);
DISPLAY 1.021277 (-200 5600);
PAINT ORANGE (-200 5600);
DISPLAY INVISIBLE (-200 5600);
FORCEPROP 1 LAST PATH I108
J 0
(-200 5550);
DISPLAY 0.978723 (-200 5550);
PAINT WHITE (-200 5550);
DISPLAY INVISIBLE (-200 5550);
FORCEPROP 2 LAST CDS_LIB mstr_discrete
J 0
(-250 5400);
PAINT MONO (-250 5400);
DISPLAY INVISIBLE (-250 5400);
FORCEPROP 1 LASTPIN (-250 5300) $PN 2
J 0
(-240 5280);
DISPLAY 0.787234 (-240 5280);
PAINT ORANGE (-240 5280);
DISPLAY INVISIBLE (-240 5280);
FORCEPROP 1 LASTPIN (-250 5500) $PN 1
J 0
(-240 5480);
DISPLAY 0.787234 (-240 5480);
PAINT ORANGE (-240 5480);
DISPLAY INVISIBLE (-240 5480);
FORCEADD CAP..1
(1475 1725);
FORCEPROP 1 LAST PART_NUMBER D97712-011
J 0
(1525 1575);
DISPLAY 0.617021 (1525 1575);
PAINT BLUE (1525 1575);
FORCEPROP 1 LAST MATERIAL X6S
J 0
(1525 1625);
DISPLAY 0.617021 (1525 1625);
PAINT SKYBLUE (1525 1625);
FORCEPROP 1 LAST TOLERANCE 10%
J 0
(1525 1675);
DISPLAY 0.617021 (1525 1675);
PAINT SKYBLUE (1525 1675);
FORCEPROP 1 LAST LOCATION C25W60
J 0
(1525 1825);
DISPLAY 0.617021 (1525 1825);
PAINT AQUA (1525 1825);
FORCEPROP 1 LAST VALUE 1.0UF
J 0
(1525 1775);
DISPLAY 0.617021 (1525 1775);
PAINT SKYBLUE (1525 1775);
FORCEPROP 1 LAST VOLTAGE 16V
J 0
(1525 1725);
DISPLAY 0.617021 (1525 1725);
PAINT SKYBLUE (1525 1725);
FORCEPROP 1 LAST PACK_TYPE 0402
J 0
(1525 1525);
DISPLAY 0.617021 (1525 1525);
PAINT SKYBLUE (1525 1525);
FORCEPROP 2 LAST CDS_LIB mstr_discrete
J 0
(1475 1725);
PAINT MONO (1475 1725);
DISPLAY INVISIBLE (1475 1725);
FORCEPROP 1 LAST PATH I109
J 0
(1525 1875);
DISPLAY 0.978723 (1525 1875);
PAINT WHITE (1525 1875);
DISPLAY INVISIBLE (1525 1875);
FORCEPROP 0 LAST BOM_COST PROC
J 0
(1525 1925);
DISPLAY 1.021277 (1525 1925);
PAINT ORANGE (1525 1925);
DISPLAY INVISIBLE (1525 1925);
FORCEPROP 0 LAST ROOM PROC_SIDEBAND
J 0
(1525 1925);
DISPLAY 1.021277 (1525 1925);
PAINT ORANGE (1525 1925);
DISPLAY INVISIBLE (1525 1925);
FORCEPROP 1 LASTPIN (1475 1625) $PN 2
J 0
(1485 1605);
DISPLAY 0.787234 (1485 1605);
PAINT ORANGE (1485 1605);
DISPLAY INVISIBLE (1485 1605);
FORCEPROP 1 LASTPIN (1475 1825) $PN 1
J 0
(1485 1805);
DISPLAY 0.787234 (1485 1805);
PAINT ORANGE (1485 1805);
DISPLAY INVISIBLE (1485 1805);
FORCEADD CAP..1
(775 4000);
FORCEPROP 1 LAST PART_NUMBER D97712-011
J 0
(825 3850);
DISPLAY 0.617021 (825 3850);
PAINT BLUE (825 3850);
FORCEPROP 1 LAST VOLTAGE 16V
J 0
(825 4000);
DISPLAY 0.617021 (825 4000);
PAINT SKYBLUE (825 4000);
FORCEPROP 1 LAST VALUE 1.0UF
J 0
(825 4050);
DISPLAY 0.617021 (825 4050);
PAINT SKYBLUE (825 4050);
FORCEPROP 1 LAST LOCATION C25W35
J 0
(825 4100);
DISPLAY 0.617021 (825 4100);
PAINT AQUA (825 4100);
FORCEPROP 1 LAST MATERIAL X6S
J 0
(825 3900);
DISPLAY 0.617021 (825 3900);
PAINT SKYBLUE (825 3900);
FORCEPROP 1 LAST TOLERANCE 10%
J 0
(825 3950);
DISPLAY 0.617021 (825 3950);
PAINT SKYBLUE (825 3950);
FORCEPROP 1 LAST PACK_TYPE 0402
J 0
(825 3800);
DISPLAY 0.617021 (825 3800);
PAINT SKYBLUE (825 3800);
FORCEPROP 0 LAST ROOM PROC_SIDEBAND
J 0
(825 4200);
DISPLAY 1.021277 (825 4200);
PAINT ORANGE (825 4200);
DISPLAY INVISIBLE (825 4200);
FORCEPROP 0 LAST BOM_COST PROC
J 0
(825 4200);
DISPLAY 1.021277 (825 4200);
PAINT ORANGE (825 4200);
DISPLAY INVISIBLE (825 4200);
FORCEPROP 1 LAST PATH I110
J 0
(825 4150);
DISPLAY 0.978723 (825 4150);
PAINT WHITE (825 4150);
DISPLAY INVISIBLE (825 4150);
FORCEPROP 2 LAST CDS_LIB mstr_discrete
J 0
(775 4000);
PAINT MONO (775 4000);
DISPLAY INVISIBLE (775 4000);
FORCEPROP 1 LASTPIN (775 3900) $PN 2
J 0
(785 3880);
DISPLAY 0.787234 (785 3880);
PAINT ORANGE (785 3880);
DISPLAY INVISIBLE (785 3880);
FORCEPROP 1 LASTPIN (775 4100) $PN 1
J 0
(785 4080);
DISPLAY 0.787234 (785 4080);
PAINT ORANGE (785 4080);
DISPLAY INVISIBLE (785 4080);
FORCEADD CAP..1
(2325 3000);
FORCEPROP 1 LAST TOLERANCE 10%
J 0
(2375 2950);
DISPLAY 0.617021 (2375 2950);
PAINT SKYBLUE (2375 2950);
FORCEPROP 1 LAST PART_NUMBER D97712-011
J 0
(2375 2850);
DISPLAY 0.617021 (2375 2850);
PAINT BLUE (2375 2850);
FORCEPROP 1 LAST VALUE 1.0UF
J 0
(2375 3050);
DISPLAY 0.617021 (2375 3050);
PAINT SKYBLUE (2375 3050);
FORCEPROP 1 LAST VOLTAGE 16V
J 0
(2375 3000);
DISPLAY 0.617021 (2375 3000);
PAINT SKYBLUE (2375 3000);
FORCEPROP 1 LAST MATERIAL X6S
J 0
(2375 2900);
DISPLAY 0.617021 (2375 2900);
PAINT SKYBLUE (2375 2900);
FORCEPROP 1 LAST PACK_TYPE 0402
J 0
(2375 2800);
DISPLAY 0.617021 (2375 2800);
PAINT SKYBLUE (2375 2800);
FORCEPROP 1 LAST LOCATION C25W48
J 0
(2375 3100);
DISPLAY 0.617021 (2375 3100);
PAINT AQUA (2375 3100);
FORCEPROP 0 LAST BOM_COST PROC
J 0
(2375 3200);
DISPLAY 1.021277 (2375 3200);
PAINT ORANGE (2375 3200);
DISPLAY INVISIBLE (2375 3200);
FORCEPROP 0 LAST ROOM PROC_SIDEBAND
J 0
(2375 3200);
DISPLAY 1.021277 (2375 3200);
PAINT ORANGE (2375 3200);
DISPLAY INVISIBLE (2375 3200);
FORCEPROP 1 LAST PATH I112
J 0
(2375 3150);
DISPLAY 0.978723 (2375 3150);
PAINT WHITE (2375 3150);
DISPLAY INVISIBLE (2375 3150);
FORCEPROP 2 LAST CDS_LIB mstr_discrete
J 0
(2325 3000);
PAINT MONO (2325 3000);
DISPLAY INVISIBLE (2325 3000);
FORCEPROP 1 LASTPIN (2325 2900) $PN 2
J 0
(2335 2880);
DISPLAY 0.787234 (2335 2880);
PAINT ORANGE (2335 2880);
DISPLAY INVISIBLE (2335 2880);
FORCEPROP 1 LASTPIN (2325 3100) $PN 1
J 0
(2335 3080);
DISPLAY 0.787234 (2335 3080);
PAINT ORANGE (2335 3080);
DISPLAY INVISIBLE (2335 3080);
FORCEADD CAP..1
(2775 3975);
FORCEPROP 1 LAST VALUE 1.0UF
J 0
(2825 4025);
DISPLAY 0.617021 (2825 4025);
PAINT SKYBLUE (2825 4025);
FORCEPROP 1 LAST VOLTAGE 16V
J 0
(2825 3975);
DISPLAY 0.617021 (2825 3975);
PAINT SKYBLUE (2825 3975);
FORCEPROP 1 LAST TOLERANCE 10%
J 0
(2825 3925);
DISPLAY 0.617021 (2825 3925);
PAINT SKYBLUE (2825 3925);
FORCEPROP 1 LAST LOCATION C25W37
J 0
(2825 4075);
DISPLAY 0.617021 (2825 4075);
PAINT AQUA (2825 4075);
FORCEPROP 1 LAST PACK_TYPE 0402
J 0
(2825 3775);
DISPLAY 0.617021 (2825 3775);
PAINT SKYBLUE (2825 3775);
FORCEPROP 1 LAST MATERIAL X6S
J 0
(2825 3875);
DISPLAY 0.617021 (2825 3875);
PAINT SKYBLUE (2825 3875);
FORCEPROP 1 LAST PART_NUMBER D97712-011
J 0
(2825 3825);
DISPLAY 0.617021 (2825 3825);
PAINT BLUE (2825 3825);
FORCEPROP 0 LAST BOM_COST PROC
J 0
(2825 4175);
DISPLAY 1.021277 (2825 4175);
PAINT ORANGE (2825 4175);
DISPLAY INVISIBLE (2825 4175);
FORCEPROP 0 LAST ROOM PROC_SIDEBAND
J 0
(2825 4175);
DISPLAY 1.021277 (2825 4175);
PAINT ORANGE (2825 4175);
DISPLAY INVISIBLE (2825 4175);
FORCEPROP 1 LAST PATH I113
J 0
(2825 4125);
DISPLAY 0.978723 (2825 4125);
PAINT WHITE (2825 4125);
DISPLAY INVISIBLE (2825 4125);
FORCEPROP 2 LAST CDS_LIB mstr_discrete
J 0
(2775 3975);
PAINT MONO (2775 3975);
DISPLAY INVISIBLE (2775 3975);
FORCEPROP 1 LASTPIN (2775 3875) $PN 2
J 0
(2785 3855);
DISPLAY 0.787234 (2785 3855);
PAINT ORANGE (2785 3855);
DISPLAY INVISIBLE (2785 3855);
FORCEPROP 1 LASTPIN (2775 4075) $PN 1
J 0
(2785 4055);
DISPLAY 0.787234 (2785 4055);
PAINT ORANGE (2785 4055);
DISPLAY INVISIBLE (2785 4055);
FORCEADD CAP..1
(3950 2900);
FORCEPROP 1 LAST PART_NUMBER D97712-011
J 0
(4000 2750);
DISPLAY 0.617021 (4000 2750);
PAINT BLUE (4000 2750);
FORCEPROP 1 LAST TOLERANCE 10%
J 0
(4000 2850);
DISPLAY 0.617021 (4000 2850);
PAINT SKYBLUE (4000 2850);
FORCEPROP 1 LAST VOLTAGE 16V
J 0
(4000 2900);
DISPLAY 0.617021 (4000 2900);
PAINT SKYBLUE (4000 2900);
FORCEPROP 1 LAST MATERIAL X6S
J 0
(4000 2800);
DISPLAY 0.617021 (4000 2800);
PAINT SKYBLUE (4000 2800);
FORCEPROP 1 LAST PACK_TYPE 0402
J 0
(4000 2700);
DISPLAY 0.617021 (4000 2700);
PAINT SKYBLUE (4000 2700);
FORCEPROP 1 LAST LOCATION C25W51
J 0
(4000 3000);
DISPLAY 0.617021 (4000 3000);
PAINT AQUA (4000 3000);
FORCEPROP 1 LAST VALUE 1.0UF
J 0
(4000 2950);
DISPLAY 0.617021 (4000 2950);
PAINT SKYBLUE (4000 2950);
FORCEPROP 0 LAST ROOM PROC_SIDEBAND
J 0
(4000 3100);
DISPLAY 1.021277 (4000 3100);
PAINT ORANGE (4000 3100);
DISPLAY INVISIBLE (4000 3100);
FORCEPROP 0 LAST BOM_COST PROC
J 0
(4000 3100);
DISPLAY 1.021277 (4000 3100);
PAINT ORANGE (4000 3100);
DISPLAY INVISIBLE (4000 3100);
FORCEPROP 1 LAST PATH I114
J 0
(4000 3050);
DISPLAY 0.978723 (4000 3050);
PAINT WHITE (4000 3050);
DISPLAY INVISIBLE (4000 3050);
FORCEPROP 2 LAST CDS_LIB mstr_discrete
J 0
(3950 2900);
PAINT MONO (3950 2900);
DISPLAY INVISIBLE (3950 2900);
FORCEPROP 1 LASTPIN (3950 2800) $PN 2
J 0
(3960 2780);
DISPLAY 0.787234 (3960 2780);
PAINT ORANGE (3960 2780);
DISPLAY INVISIBLE (3960 2780);
FORCEPROP 1 LASTPIN (3950 3000) $PN 1
J 0
(3960 2980);
DISPLAY 0.787234 (3960 2980);
PAINT ORANGE (3960 2980);
DISPLAY INVISIBLE (3960 2980);
FORCEADD CAP..1
(4800 5300);
FORCEPROP 1 LAST LOCATION C25W71
J 0
(4850 5400);
DISPLAY 0.617021 (4850 5400);
PAINT AQUA (4850 5400);
FORCEPROP 1 LAST VOLTAGE 16V
J 0
(4850 5300);
DISPLAY 0.617021 (4850 5300);
PAINT SKYBLUE (4850 5300);
FORCEPROP 1 LAST TOLERANCE 10%
J 0
(4850 5250);
DISPLAY 0.617021 (4850 5250);
PAINT SKYBLUE (4850 5250);
FORCEPROP 1 LAST VALUE 1.0UF
J 0
(4850 5350);
DISPLAY 0.617021 (4850 5350);
PAINT SKYBLUE (4850 5350);
FORCEPROP 1 LAST PACK_TYPE 0402
J 0
(4850 5100);
DISPLAY 0.617021 (4850 5100);
PAINT SKYBLUE (4850 5100);
FORCEPROP 1 LAST PART_NUMBER D97712-011
J 0
(4850 5150);
DISPLAY 0.617021 (4850 5150);
PAINT BLUE (4850 5150);
FORCEPROP 1 LAST MATERIAL X6S
J 0
(4850 5200);
DISPLAY 0.617021 (4850 5200);
PAINT SKYBLUE (4850 5200);
FORCEPROP 0 LAST ROOM PROC_SIDEBAND
J 0
(4850 5500);
DISPLAY 1.021277 (4850 5500);
PAINT ORANGE (4850 5500);
DISPLAY INVISIBLE (4850 5500);
FORCEPROP 0 LAST BOM_COST PROC
J 0
(4850 5500);
DISPLAY 1.021277 (4850 5500);
PAINT ORANGE (4850 5500);
DISPLAY INVISIBLE (4850 5500);
FORCEPROP 1 LAST PATH I115
J 0
(4850 5450);
DISPLAY 0.978723 (4850 5450);
PAINT WHITE (4850 5450);
DISPLAY INVISIBLE (4850 5450);
FORCEPROP 2 LAST CDS_LIB mstr_discrete
J 0
(4800 5300);
PAINT MONO (4800 5300);
DISPLAY INVISIBLE (4800 5300);
FORCEPROP 1 LASTPIN (4800 5200) $PN 2
J 0
(4810 5180);
DISPLAY 0.787234 (4810 5180);
PAINT ORANGE (4810 5180);
DISPLAY INVISIBLE (4810 5180);
FORCEPROP 1 LASTPIN (4800 5400) $PN 1
J 0
(4810 5380);
DISPLAY 0.787234 (4810 5380);
PAINT ORANGE (4810 5380);
DISPLAY INVISIBLE (4810 5380);
FORCEADD CAP..1
(2150 5175);
FORCEPROP 1 LAST VOLTAGE 16V
J 0
(2200 5175);
DISPLAY 0.617021 (2200 5175);
PAINT SKYBLUE (2200 5175);
FORCEPROP 1 LAST VALUE 1.0UF
J 0
(2200 5225);
DISPLAY 0.617021 (2200 5225);
PAINT SKYBLUE (2200 5225);
FORCEPROP 1 LAST LOCATION C25W66
J 0
(2200 5275);
DISPLAY 0.617021 (2200 5275);
PAINT AQUA (2200 5275);
FORCEPROP 1 LAST TOLERANCE 10%
J 0
(2200 5125);
DISPLAY 0.617021 (2200 5125);
PAINT SKYBLUE (2200 5125);
FORCEPROP 1 LAST PACK_TYPE 0402
J 0
(2200 4975);
DISPLAY 0.617021 (2200 4975);
PAINT SKYBLUE (2200 4975);
FORCEPROP 1 LAST MATERIAL X6S
J 0
(2200 5075);
DISPLAY 0.617021 (2200 5075);
PAINT SKYBLUE (2200 5075);
FORCEPROP 1 LAST PART_NUMBER D97712-011
J 0
(2200 5025);
DISPLAY 0.617021 (2200 5025);
PAINT BLUE (2200 5025);
FORCEPROP 0 LAST ROOM PROC_SIDEBAND
J 0
(2200 5375);
DISPLAY 1.021277 (2200 5375);
PAINT ORANGE (2200 5375);
DISPLAY INVISIBLE (2200 5375);
FORCEPROP 0 LAST BOM_COST PROC
J 0
(2200 5375);
DISPLAY 1.021277 (2200 5375);
PAINT ORANGE (2200 5375);
DISPLAY INVISIBLE (2200 5375);
FORCEPROP 1 LAST PATH I116
J 0
(2200 5325);
DISPLAY 0.978723 (2200 5325);
PAINT WHITE (2200 5325);
DISPLAY INVISIBLE (2200 5325);
FORCEPROP 2 LAST CDS_LIB mstr_discrete
J 0
(2150 5175);
PAINT MONO (2150 5175);
DISPLAY INVISIBLE (2150 5175);
FORCEPROP 1 LASTPIN (2150 5075) $PN 2
J 0
(2160 5055);
DISPLAY 0.787234 (2160 5055);
PAINT ORANGE (2160 5055);
DISPLAY INVISIBLE (2160 5055);
FORCEPROP 1 LASTPIN (2150 5275) $PN 1
J 0
(2160 5255);
DISPLAY 0.787234 (2160 5255);
PAINT ORANGE (2160 5255);
DISPLAY INVISIBLE (2160 5255);
FORCEADD CAP..1
(2400 5175);
FORCEPROP 1 LAST VALUE 1.0UF
J 0
(2450 5225);
DISPLAY 0.617021 (2450 5225);
PAINT SKYBLUE (2450 5225);
FORCEPROP 1 LAST TOLERANCE 10%
J 0
(2450 5125);
DISPLAY 0.617021 (2450 5125);
PAINT SKYBLUE (2450 5125);
FORCEPROP 1 LAST VOLTAGE 16V
J 0
(2450 5175);
DISPLAY 0.617021 (2450 5175);
PAINT SKYBLUE (2450 5175);
FORCEPROP 1 LAST LOCATION C25W67
J 0
(2450 5275);
DISPLAY 0.617021 (2450 5275);
PAINT AQUA (2450 5275);
FORCEPROP 1 LAST PACK_TYPE 0402
J 0
(2450 4975);
DISPLAY 0.617021 (2450 4975);
PAINT SKYBLUE (2450 4975);
FORCEPROP 1 LAST PART_NUMBER D97712-011
J 0
(2450 5025);
DISPLAY 0.617021 (2450 5025);
PAINT BLUE (2450 5025);
FORCEPROP 1 LAST MATERIAL X6S
J 0
(2450 5075);
DISPLAY 0.617021 (2450 5075);
PAINT SKYBLUE (2450 5075);
FORCEPROP 0 LAST BOM_COST PROC
J 0
(2450 5375);
DISPLAY 1.021277 (2450 5375);
PAINT ORANGE (2450 5375);
DISPLAY INVISIBLE (2450 5375);
FORCEPROP 0 LAST ROOM PROC_SIDEBAND
J 0
(2450 5375);
DISPLAY 1.021277 (2450 5375);
PAINT ORANGE (2450 5375);
DISPLAY INVISIBLE (2450 5375);
FORCEPROP 1 LAST PATH I117
J 0
(2450 5325);
DISPLAY 0.978723 (2450 5325);
PAINT WHITE (2450 5325);
DISPLAY INVISIBLE (2450 5325);
FORCEPROP 2 LAST CDS_LIB mstr_discrete
J 0
(2400 5175);
PAINT MONO (2400 5175);
DISPLAY INVISIBLE (2400 5175);
FORCEPROP 1 LASTPIN (2400 5075) $PN 2
J 0
(2410 5055);
DISPLAY 0.787234 (2410 5055);
PAINT ORANGE (2410 5055);
DISPLAY INVISIBLE (2410 5055);
FORCEPROP 1 LASTPIN (2400 5275) $PN 1
J 0
(2410 5255);
DISPLAY 0.787234 (2410 5255);
PAINT ORANGE (2410 5255);
DISPLAY INVISIBLE (2410 5255);
FORCEADD CAP..1
(4250 2900);
FORCEPROP 1 LAST LOCATION C25W52
J 0
(4300 3000);
DISPLAY 0.617021 (4300 3000);
PAINT AQUA (4300 3000);
FORCEPROP 1 LAST PART_NUMBER D97712-011
J 0
(4300 2750);
DISPLAY 0.617021 (4300 2750);
PAINT BLUE (4300 2750);
FORCEPROP 1 LAST VALUE 1.0UF
J 0
(4300 2950);
DISPLAY 0.617021 (4300 2950);
PAINT SKYBLUE (4300 2950);
FORCEPROP 1 LAST TOLERANCE 10%
J 0
(4300 2850);
DISPLAY 0.617021 (4300 2850);
PAINT SKYBLUE (4300 2850);
FORCEPROP 1 LAST VOLTAGE 16V
J 0
(4300 2900);
DISPLAY 0.617021 (4300 2900);
PAINT SKYBLUE (4300 2900);
FORCEPROP 1 LAST MATERIAL X6S
J 0
(4300 2800);
DISPLAY 0.617021 (4300 2800);
PAINT SKYBLUE (4300 2800);
FORCEPROP 1 LAST PACK_TYPE 0402
J 0
(4300 2700);
DISPLAY 0.617021 (4300 2700);
PAINT SKYBLUE (4300 2700);
FORCEPROP 2 LAST CDS_LIB mstr_discrete
J 0
(4250 2900);
PAINT MONO (4250 2900);
DISPLAY INVISIBLE (4250 2900);
FORCEPROP 1 LAST PATH I118
J 0
(4300 3050);
DISPLAY 0.978723 (4300 3050);
PAINT WHITE (4300 3050);
DISPLAY INVISIBLE (4300 3050);
FORCEPROP 0 LAST BOM_COST PROC
J 0
(4300 3100);
DISPLAY 1.021277 (4300 3100);
PAINT ORANGE (4300 3100);
DISPLAY INVISIBLE (4300 3100);
FORCEPROP 0 LAST ROOM PROC_SIDEBAND
J 0
(4300 3100);
DISPLAY 1.021277 (4300 3100);
PAINT ORANGE (4300 3100);
DISPLAY INVISIBLE (4300 3100);
FORCEPROP 1 LASTPIN (4250 2800) $PN 2
J 0
(4260 2780);
DISPLAY 0.787234 (4260 2780);
PAINT ORANGE (4260 2780);
DISPLAY INVISIBLE (4260 2780);
FORCEPROP 1 LASTPIN (4250 3000) $PN 1
J 0
(4260 2980);
DISPLAY 0.787234 (4260 2980);
PAINT ORANGE (4260 2980);
DISPLAY INVISIBLE (4260 2980);
FORCEADD CAP_A..1
(-1475 4125);
FORCEPROP 1 LAST TOLERANCE 10%
J 0
(-1425 4075);
DISPLAY 0.617021 (-1425 4075);
PAINT SKYBLUE (-1425 4075);
FORCEPROP 1 LAST MATERIAL X7R
J 0
(-1425 4025);
DISPLAY 0.617021 (-1425 4025);
PAINT SKYBLUE (-1425 4025);
FORCEPROP 1 LAST PACK_TYPE 0402V
J 0
(-1425 3925);
DISPLAY 0.617021 (-1425 3925);
PAINT SKYBLUE (-1425 3925);
FORCEPROP 1 LASTPIN (-1475 4225) $PN 1
J 0
(-1465 4205);
DISPLAY 0.617021 (-1465 4205);
PAINT ORANGE (-1465 4205);
FORCEPROP 1 LAST VOLTAGE 16V
J 0
(-1425 4125);
DISPLAY 0.617021 (-1425 4125);
PAINT SKYBLUE (-1425 4125);
FORCEPROP 1 LAST PART_NUMBER A36096-030
J 0
(-1425 3975);
DISPLAY 0.617021 (-1425 3975);
PAINT BLUE (-1425 3975);
FORCEPROP 1 LAST VALUE 0.1UF
J 0
(-1425 4175);
DISPLAY 0.617021 (-1425 4175);
PAINT SKYBLUE (-1425 4175);
FORCEPROP 1 LAST LOCATION C25W31
J 0
(-1425 4225);
DISPLAY 0.617021 (-1425 4225);
PAINT AQUA (-1425 4225);
FORCEPROP 1 LASTPIN (-1475 4025) $PN 2
J 0
(-1465 4005);
DISPLAY 0.617021 (-1465 4005);
PAINT ORANGE (-1465 4005);
FORCEPROP 2 LAST CDS_LOCATION C25W31
J 0
(-1425 4225);
DISPLAY 0.617021 (-1425 4225);
PAINT AQUA (-1425 4225);
DISPLAY INVISIBLE (-1425 4225);
FORCEPROP 2 LAST SEC 1
J 0
(-1425 4350);
DISPLAY 0.680851 (-1425 4350);
PAINT MONO (-1425 4350);
DISPLAY INVISIBLE (-1425 4350);
FORCEPROP 2 LAST SEC_TYPE 0402V
J 0
(-1425 4350);
DISPLAY 1.021277 (-1425 4350);
PAINT ORANGE (-1425 4350);
DISPLAY INVISIBLE (-1425 4350);
FORCEPROP 2 LAST ROOM VDDQ_KLM_PWR_VR
J 0
(-1425 4275);
DISPLAY 1.361702 (-1425 4275);
PAINT ORANGE (-1425 4275);
DISPLAY INVISIBLE (-1425 4275);
FORCEPROP 2 LAST CDS_SEC 1
J 0
(-1425 4275);
PAINT ORANGE (-1425 4275);
DISPLAY INVISIBLE (-1425 4275);
FORCEPROP 2 LAST CDS_LIB dev_discrete
J 0
(-1475 4125);
PAINT ORANGE (-1475 4125);
DISPLAY INVISIBLE (-1475 4125);
FORCEPROP 1 LAST PATH I119
J 0
(-1425 4275);
DISPLAY 0.978723 (-1425 4275);
PAINT WHITE (-1425 4275);
DISPLAY INVISIBLE (-1425 4275);
FORCEADD CAP_A..1
(425 4000);
FORCEPROP 1 LAST TOLERANCE 10%
J 0
(475 3950);
DISPLAY 0.617021 (475 3950);
PAINT SKYBLUE (475 3950);
FORCEPROP 1 LAST MATERIAL X7R
J 0
(475 3900);
DISPLAY 0.617021 (475 3900);
PAINT SKYBLUE (475 3900);
FORCEPROP 1 LAST PACK_TYPE 0402V
J 0
(475 3800);
DISPLAY 0.617021 (475 3800);
PAINT SKYBLUE (475 3800);
FORCEPROP 1 LASTPIN (425 4100) $PN 1
J 0
(435 4080);
DISPLAY 0.617021 (435 4080);
PAINT ORANGE (435 4080);
FORCEPROP 1 LASTPIN (425 3900) $PN 2
J 0
(435 3880);
DISPLAY 0.617021 (435 3880);
PAINT ORANGE (435 3880);
FORCEPROP 1 LAST VOLTAGE 16V
J 0
(475 4000);
DISPLAY 0.617021 (475 4000);
PAINT SKYBLUE (475 4000);
FORCEPROP 1 LAST PART_NUMBER A36096-030
J 0
(475 3850);
DISPLAY 0.617021 (475 3850);
PAINT BLUE (475 3850);
FORCEPROP 1 LAST VALUE 0.1UF
J 0
(475 4050);
DISPLAY 0.617021 (475 4050);
PAINT SKYBLUE (475 4050);
FORCEPROP 1 LAST LOCATION C25W34
J 0
(475 4100);
DISPLAY 0.617021 (475 4100);
PAINT AQUA (475 4100);
FORCEPROP 2 LAST CDS_LOCATION C25W34
J 0
(475 4100);
DISPLAY 0.617021 (475 4100);
PAINT AQUA (475 4100);
DISPLAY INVISIBLE (475 4100);
FORCEPROP 2 LAST SEC 1
J 0
(475 4225);
DISPLAY 0.680851 (475 4225);
PAINT MONO (475 4225);
DISPLAY INVISIBLE (475 4225);
FORCEPROP 2 LAST SEC_TYPE 0402V
J 0
(475 4225);
DISPLAY 1.021277 (475 4225);
PAINT ORANGE (475 4225);
DISPLAY INVISIBLE (475 4225);
FORCEPROP 2 LAST ROOM VDDQ_KLM_PWR_VR
J 0
(475 4150);
DISPLAY 1.361702 (475 4150);
PAINT ORANGE (475 4150);
DISPLAY INVISIBLE (475 4150);
FORCEPROP 2 LAST CDS_SEC 1
J 0
(475 4150);
PAINT ORANGE (475 4150);
DISPLAY INVISIBLE (475 4150);
FORCEPROP 2 LAST CDS_LIB dev_discrete
J 0
(425 4000);
PAINT ORANGE (425 4000);
DISPLAY INVISIBLE (425 4000);
FORCEPROP 1 LAST PATH I120
J 0
(475 4150);
DISPLAY 0.978723 (475 4150);
PAINT WHITE (475 4150);
DISPLAY INVISIBLE (475 4150);
FORCEADD CAP_A..1
(3325 3975);
FORCEPROP 1 LAST VOLTAGE 16V
J 0
(3375 3975);
DISPLAY 0.617021 (3375 3975);
PAINT SKYBLUE (3375 3975);
FORCEPROP 1 LAST TOLERANCE 10%
J 0
(3375 3925);
DISPLAY 0.617021 (3375 3925);
PAINT SKYBLUE (3375 3925);
FORCEPROP 1 LAST MATERIAL X7R
J 0
(3375 3875);
DISPLAY 0.617021 (3375 3875);
PAINT SKYBLUE (3375 3875);
FORCEPROP 1 LAST PACK_TYPE 0402V
J 0
(3375 3775);
DISPLAY 0.617021 (3375 3775);
PAINT SKYBLUE (3375 3775);
FORCEPROP 1 LASTPIN (3325 4075) $PN 1
J 0
(3335 4055);
DISPLAY 0.617021 (3335 4055);
PAINT ORANGE (3335 4055);
FORCEPROP 1 LASTPIN (3325 3875) $PN 2
J 0
(3335 3855);
DISPLAY 0.617021 (3335 3855);
PAINT ORANGE (3335 3855);
FORCEPROP 1 LAST LOCATION C25W38
J 0
(3375 4075);
DISPLAY 0.617021 (3375 4075);
PAINT AQUA (3375 4075);
FORCEPROP 1 LAST VALUE 0.1UF
J 0
(3375 4025);
DISPLAY 0.617021 (3375 4025);
PAINT SKYBLUE (3375 4025);
FORCEPROP 1 LAST PART_NUMBER A36096-030
J 0
(3375 3825);
DISPLAY 0.617021 (3375 3825);
PAINT BLUE (3375 3825);
FORCEPROP 2 LAST CDS_LOCATION C25W38
J 0
(3375 4075);
DISPLAY 0.617021 (3375 4075);
PAINT AQUA (3375 4075);
DISPLAY INVISIBLE (3375 4075);
FORCEPROP 2 LAST SEC 1
J 0
(3375 4200);
DISPLAY 0.680851 (3375 4200);
PAINT MONO (3375 4200);
DISPLAY INVISIBLE (3375 4200);
FORCEPROP 2 LAST SEC_TYPE 0402V
J 0
(3375 4200);
DISPLAY 1.021277 (3375 4200);
PAINT ORANGE (3375 4200);
DISPLAY INVISIBLE (3375 4200);
FORCEPROP 2 LAST ROOM VDDQ_KLM_PWR_VR
J 0
(3375 4125);
DISPLAY 1.361702 (3375 4125);
PAINT ORANGE (3375 4125);
DISPLAY INVISIBLE (3375 4125);
FORCEPROP 2 LAST CDS_SEC 1
J 0
(3375 4125);
PAINT ORANGE (3375 4125);
DISPLAY INVISIBLE (3375 4125);
FORCEPROP 2 LAST CDS_LIB dev_discrete
J 0
(3325 3975);
PAINT ORANGE (3325 3975);
DISPLAY INVISIBLE (3325 3975);
FORCEPROP 1 LAST PATH I121
J 0
(3375 4125);
DISPLAY 0.978723 (3375 4125);
PAINT WHITE (3375 4125);
DISPLAY INVISIBLE (3375 4125);
FORCEADD CAP_A..1
(-100 2900);
FORCEPROP 1 LAST TOLERANCE 10%
J 0
(-50 2850);
DISPLAY 0.617021 (-50 2850);
PAINT SKYBLUE (-50 2850);
FORCEPROP 1 LAST VOLTAGE 16V
J 0
(-50 2900);
DISPLAY 0.617021 (-50 2900);
PAINT SKYBLUE (-50 2900);
FORCEPROP 1 LAST MATERIAL X7R
J 0
(-50 2800);
DISPLAY 0.617021 (-50 2800);
PAINT SKYBLUE (-50 2800);
FORCEPROP 1 LAST PACK_TYPE 0402V
J 0
(-50 2700);
DISPLAY 0.617021 (-50 2700);
PAINT SKYBLUE (-50 2700);
FORCEPROP 1 LASTPIN (-100 2800) $PN 2
J 0
(-90 2780);
DISPLAY 0.617021 (-90 2780);
PAINT ORANGE (-90 2780);
FORCEPROP 1 LAST PART_NUMBER A36096-030
J 0
(-50 2750);
DISPLAY 0.617021 (-50 2750);
PAINT BLUE (-50 2750);
FORCEPROP 1 LAST VALUE 0.1UF
J 0
(-50 2950);
DISPLAY 0.617021 (-50 2950);
PAINT SKYBLUE (-50 2950);
FORCEPROP 1 LAST LOCATION C25W45
J 0
(-50 3000);
DISPLAY 0.617021 (-50 3000);
PAINT AQUA (-50 3000);
FORCEPROP 1 LASTPIN (-100 3000) $PN 1
J 0
(-90 2980);
DISPLAY 0.617021 (-90 2980);
PAINT ORANGE (-90 2980);
FORCEPROP 2 LAST CDS_LOCATION C25W45
J 0
(-50 3000);
DISPLAY 0.617021 (-50 3000);
PAINT AQUA (-50 3000);
DISPLAY INVISIBLE (-50 3000);
FORCEPROP 2 LAST SEC 1
J 0
(-50 3125);
DISPLAY 0.680851 (-50 3125);
PAINT MONO (-50 3125);
DISPLAY INVISIBLE (-50 3125);
FORCEPROP 2 LAST SEC_TYPE 0402V
J 0
(-50 3125);
DISPLAY 1.021277 (-50 3125);
PAINT ORANGE (-50 3125);
DISPLAY INVISIBLE (-50 3125);
FORCEPROP 2 LAST ROOM VDDQ_KLM_PWR_VR
J 0
(-50 3050);
DISPLAY 1.361702 (-50 3050);
PAINT ORANGE (-50 3050);
DISPLAY INVISIBLE (-50 3050);
FORCEPROP 2 LAST CDS_SEC 1
J 0
(-50 3050);
PAINT ORANGE (-50 3050);
DISPLAY INVISIBLE (-50 3050);
FORCEPROP 2 LAST CDS_LIB dev_discrete
J 0
(-100 2900);
PAINT ORANGE (-100 2900);
DISPLAY INVISIBLE (-100 2900);
FORCEPROP 1 LAST PATH I122
J 0
(-50 3050);
DISPLAY 0.978723 (-50 3050);
PAINT WHITE (-50 3050);
DISPLAY INVISIBLE (-50 3050);
FORCEADD CAP_A..1
(2875 3000);
FORCEPROP 1 LAST MATERIAL X7R
J 0
(2925 2900);
DISPLAY 0.617021 (2925 2900);
PAINT SKYBLUE (2925 2900);
FORCEPROP 1 LAST VALUE 0.1UF
J 0
(2925 3050);
DISPLAY 0.617021 (2925 3050);
PAINT SKYBLUE (2925 3050);
FORCEPROP 1 LASTPIN (2875 2900) $PN 2
J 0
(2885 2880);
DISPLAY 0.617021 (2885 2880);
PAINT ORANGE (2885 2880);
FORCEPROP 1 LAST PACK_TYPE 0402V
J 0
(2925 2800);
DISPLAY 0.617021 (2925 2800);
PAINT SKYBLUE (2925 2800);
FORCEPROP 1 LAST LOCATION C25W49
J 0
(2925 3100);
DISPLAY 0.617021 (2925 3100);
PAINT AQUA (2925 3100);
FORCEPROP 1 LASTPIN (2875 3100) $PN 1
J 0
(2885 3080);
DISPLAY 0.617021 (2885 3080);
PAINT ORANGE (2885 3080);
FORCEPROP 1 LAST VOLTAGE 16V
J 0
(2925 3000);
DISPLAY 0.617021 (2925 3000);
PAINT SKYBLUE (2925 3000);
FORCEPROP 1 LAST TOLERANCE 10%
J 0
(2925 2950);
DISPLAY 0.617021 (2925 2950);
PAINT SKYBLUE (2925 2950);
FORCEPROP 1 LAST PART_NUMBER A36096-030
J 0
(2925 2850);
DISPLAY 0.617021 (2925 2850);
PAINT BLUE (2925 2850);
FORCEPROP 2 LAST CDS_LOCATION C25W49
J 0
(2925 3100);
DISPLAY 0.617021 (2925 3100);
PAINT AQUA (2925 3100);
DISPLAY INVISIBLE (2925 3100);
FORCEPROP 1 LAST PATH I123
J 0
(2925 3150);
DISPLAY 0.978723 (2925 3150);
PAINT WHITE (2925 3150);
DISPLAY INVISIBLE (2925 3150);
FORCEPROP 2 LAST CDS_LIB dev_discrete
J 0
(2875 3000);
PAINT ORANGE (2875 3000);
DISPLAY INVISIBLE (2875 3000);
FORCEPROP 2 LAST CDS_SEC 1
J 0
(2925 3150);
PAINT ORANGE (2925 3150);
DISPLAY INVISIBLE (2925 3150);
FORCEPROP 2 LAST ROOM VDDQ_KLM_PWR_VR
J 0
(2925 3150);
DISPLAY 1.361702 (2925 3150);
PAINT ORANGE (2925 3150);
DISPLAY INVISIBLE (2925 3150);
FORCEPROP 2 LAST SEC_TYPE 0402V
J 0
(2925 3225);
DISPLAY 1.021277 (2925 3225);
PAINT ORANGE (2925 3225);
DISPLAY INVISIBLE (2925 3225);
FORCEPROP 2 LAST SEC 1
J 0
(2925 3225);
DISPLAY 0.680851 (2925 3225);
PAINT MONO (2925 3225);
DISPLAY INVISIBLE (2925 3225);
FORCEADD CAP_A..1
(5000 2925);
FORCEPROP 1 LASTPIN (5000 3025) $PN 1
J 0
(5010 3005);
DISPLAY 0.617021 (5010 3005);
PAINT ORANGE (5010 3005);
FORCEPROP 1 LASTPIN (5000 2825) $PN 2
J 0
(5010 2805);
DISPLAY 0.617021 (5010 2805);
PAINT ORANGE (5010 2805);
FORCEPROP 1 LAST VOLTAGE 16V
J 0
(5050 2925);
DISPLAY 0.617021 (5050 2925);
PAINT SKYBLUE (5050 2925);
FORCEPROP 1 LAST LOCATION C25W55
J 0
(5050 3025);
DISPLAY 0.617021 (5050 3025);
PAINT AQUA (5050 3025);
FORCEPROP 1 LAST VALUE 0.1UF
J 0
(5050 2975);
DISPLAY 0.617021 (5050 2975);
PAINT SKYBLUE (5050 2975);
FORCEPROP 1 LAST TOLERANCE 10%
J 0
(5050 2875);
DISPLAY 0.617021 (5050 2875);
PAINT SKYBLUE (5050 2875);
FORCEPROP 1 LAST MATERIAL X7R
J 0
(5050 2825);
DISPLAY 0.617021 (5050 2825);
PAINT SKYBLUE (5050 2825);
FORCEPROP 1 LAST PART_NUMBER A36096-030
J 0
(5050 2775);
DISPLAY 0.617021 (5050 2775);
PAINT BLUE (5050 2775);
FORCEPROP 1 LAST PACK_TYPE 0402V
J 0
(5050 2725);
DISPLAY 0.617021 (5050 2725);
PAINT SKYBLUE (5050 2725);
FORCEPROP 2 LAST CDS_LOCATION C25W55
J 0
(5050 3025);
DISPLAY 0.617021 (5050 3025);
PAINT AQUA (5050 3025);
DISPLAY INVISIBLE (5050 3025);
FORCEPROP 2 LAST SEC 1
J 0
(5050 3150);
DISPLAY 0.680851 (5050 3150);
PAINT MONO (5050 3150);
DISPLAY INVISIBLE (5050 3150);
FORCEPROP 2 LAST SEC_TYPE 0402V
J 0
(5050 3150);
DISPLAY 1.021277 (5050 3150);
PAINT ORANGE (5050 3150);
DISPLAY INVISIBLE (5050 3150);
FORCEPROP 2 LAST ROOM VDDQ_KLM_PWR_VR
J 0
(5050 3075);
DISPLAY 1.361702 (5050 3075);
PAINT ORANGE (5050 3075);
DISPLAY INVISIBLE (5050 3075);
FORCEPROP 2 LAST CDS_SEC 1
J 0
(5050 3075);
PAINT ORANGE (5050 3075);
DISPLAY INVISIBLE (5050 3075);
FORCEPROP 2 LAST CDS_LIB dev_discrete
J 0
(5000 2925);
PAINT ORANGE (5000 2925);
DISPLAY INVISIBLE (5000 2925);
FORCEPROP 1 LAST PATH I124
J 0
(5050 3075);
DISPLAY 0.978723 (5050 3075);
PAINT WHITE (5050 3075);
DISPLAY INVISIBLE (5050 3075);
FORCEADD CAP_A..1
(-1150 1850);
FORCEPROP 1 LAST PACK_TYPE 0402V
J 0
(-1100 1650);
DISPLAY 0.617021 (-1100 1650);
PAINT SKYBLUE (-1100 1650);
FORCEPROP 1 LASTPIN (-1150 1750) $PN 2
J 0
(-1140 1730);
DISPLAY 0.617021 (-1140 1730);
PAINT ORANGE (-1140 1730);
FORCEPROP 1 LAST LOCATION C25W58
J 0
(-1100 1950);
DISPLAY 0.617021 (-1100 1950);
PAINT AQUA (-1100 1950);
FORCEPROP 1 LAST VALUE 0.1UF
J 0
(-1100 1900);
DISPLAY 0.617021 (-1100 1900);
PAINT SKYBLUE (-1100 1900);
FORCEPROP 1 LASTPIN (-1150 1950) $PN 1
J 0
(-1140 1930);
DISPLAY 0.617021 (-1140 1930);
PAINT ORANGE (-1140 1930);
FORCEPROP 1 LAST VOLTAGE 16V
J 0
(-1100 1850);
DISPLAY 0.617021 (-1100 1850);
PAINT SKYBLUE (-1100 1850);
FORCEPROP 1 LAST TOLERANCE 10%
J 0
(-1100 1800);
DISPLAY 0.617021 (-1100 1800);
PAINT SKYBLUE (-1100 1800);
FORCEPROP 1 LAST PART_NUMBER A36096-030
J 0
(-1100 1700);
DISPLAY 0.617021 (-1100 1700);
PAINT BLUE (-1100 1700);
FORCEPROP 1 LAST MATERIAL X7R
J 0
(-1100 1750);
DISPLAY 0.617021 (-1100 1750);
PAINT SKYBLUE (-1100 1750);
FORCEPROP 2 LAST CDS_LOCATION C25W58
J 0
(-1100 1950);
DISPLAY 0.617021 (-1100 1950);
PAINT AQUA (-1100 1950);
DISPLAY INVISIBLE (-1100 1950);
FORCEPROP 2 LAST SEC 1
J 0
(-1100 2075);
DISPLAY 0.680851 (-1100 2075);
PAINT MONO (-1100 2075);
DISPLAY INVISIBLE (-1100 2075);
FORCEPROP 2 LAST SEC_TYPE 0402V
J 0
(-1100 2075);
DISPLAY 1.021277 (-1100 2075);
PAINT ORANGE (-1100 2075);
DISPLAY INVISIBLE (-1100 2075);
FORCEPROP 2 LAST ROOM VDDQ_KLM_PWR_VR
J 0
(-1100 2000);
DISPLAY 1.361702 (-1100 2000);
PAINT ORANGE (-1100 2000);
DISPLAY INVISIBLE (-1100 2000);
FORCEPROP 2 LAST CDS_SEC 1
J 0
(-1100 2000);
PAINT ORANGE (-1100 2000);
DISPLAY INVISIBLE (-1100 2000);
FORCEPROP 2 LAST CDS_LIB dev_discrete
J 0
(-1150 1850);
PAINT ORANGE (-1150 1850);
DISPLAY INVISIBLE (-1150 1850);
FORCEPROP 1 LAST PATH I125
J 0
(-1100 2000);
DISPLAY 0.978723 (-1100 2000);
PAINT WHITE (-1100 2000);
DISPLAY INVISIBLE (-1100 2000);
FORCEADD CAP_A..1
(2025 1750);
FORCEPROP 1 LAST LOCATION C25W61
J 0
(2075 1850);
DISPLAY 0.617021 (2075 1850);
PAINT AQUA (2075 1850);
FORCEPROP 1 LAST TOLERANCE 10%
J 0
(2075 1700);
DISPLAY 0.617021 (2075 1700);
PAINT SKYBLUE (2075 1700);
FORCEPROP 1 LAST MATERIAL X7R
J 0
(2075 1650);
DISPLAY 0.617021 (2075 1650);
PAINT SKYBLUE (2075 1650);
FORCEPROP 1 LAST PACK_TYPE 0402V
J 0
(2075 1550);
DISPLAY 0.617021 (2075 1550);
PAINT SKYBLUE (2075 1550);
FORCEPROP 1 LASTPIN (2025 1850) $PN 1
J 0
(2035 1830);
DISPLAY 0.617021 (2035 1830);
PAINT ORANGE (2035 1830);
FORCEPROP 1 LASTPIN (2025 1650) $PN 2
J 0
(2035 1630);
DISPLAY 0.617021 (2035 1630);
PAINT ORANGE (2035 1630);
FORCEPROP 1 LAST VOLTAGE 16V
J 0
(2075 1750);
DISPLAY 0.617021 (2075 1750);
PAINT SKYBLUE (2075 1750);
FORCEPROP 1 LAST PART_NUMBER A36096-030
J 0
(2075 1600);
DISPLAY 0.617021 (2075 1600);
PAINT BLUE (2075 1600);
FORCEPROP 1 LAST VALUE 0.1UF
J 0
(2075 1800);
DISPLAY 0.617021 (2075 1800);
PAINT SKYBLUE (2075 1800);
FORCEPROP 2 LAST CDS_LOCATION C25W61
J 0
(2075 1850);
DISPLAY 0.617021 (2075 1850);
PAINT AQUA (2075 1850);
DISPLAY INVISIBLE (2075 1850);
FORCEPROP 2 LAST SEC 1
J 0
(2075 1975);
DISPLAY 0.680851 (2075 1975);
PAINT MONO (2075 1975);
DISPLAY INVISIBLE (2075 1975);
FORCEPROP 2 LAST SEC_TYPE 0402V
J 0
(2075 1975);
DISPLAY 1.021277 (2075 1975);
PAINT ORANGE (2075 1975);
DISPLAY INVISIBLE (2075 1975);
FORCEPROP 2 LAST ROOM VDDQ_KLM_PWR_VR
J 0
(2075 1900);
DISPLAY 1.361702 (2075 1900);
PAINT ORANGE (2075 1900);
DISPLAY INVISIBLE (2075 1900);
FORCEPROP 2 LAST CDS_SEC 1
J 0
(2075 1900);
PAINT ORANGE (2075 1900);
DISPLAY INVISIBLE (2075 1900);
FORCEPROP 2 LAST CDS_LIB dev_discrete
J 0
(2025 1750);
PAINT ORANGE (2025 1750);
DISPLAY INVISIBLE (2025 1750);
FORCEPROP 1 LAST PATH I126
J 0
(2075 1900);
DISPLAY 0.978723 (2075 1900);
PAINT WHITE (2075 1900);
DISPLAY INVISIBLE (2075 1900);
FORCEADD CAP_A..1
(2700 5175);
FORCEPROP 1 LAST TOLERANCE 10%
J 0
(2750 5125);
DISPLAY 0.617021 (2750 5125);
PAINT SKYBLUE (2750 5125);
FORCEPROP 1 LAST VOLTAGE 16V
J 0
(2750 5175);
DISPLAY 0.617021 (2750 5175);
PAINT SKYBLUE (2750 5175);
FORCEPROP 1 LAST LOCATION C25W68
J 0
(2750 5275);
DISPLAY 0.617021 (2750 5275);
PAINT AQUA (2750 5275);
FORCEPROP 1 LAST VALUE 0.1UF
J 0
(2750 5225);
DISPLAY 0.617021 (2750 5225);
PAINT SKYBLUE (2750 5225);
FORCEPROP 1 LAST PART_NUMBER A36096-030
J 0
(2750 5025);
DISPLAY 0.617021 (2750 5025);
PAINT BLUE (2750 5025);
FORCEPROP 1 LASTPIN (2700 5075) $PN 2
J 0
(2710 5055);
DISPLAY 0.617021 (2710 5055);
PAINT ORANGE (2710 5055);
FORCEPROP 1 LASTPIN (2700 5275) $PN 1
J 0
(2710 5255);
DISPLAY 0.617021 (2710 5255);
PAINT ORANGE (2710 5255);
FORCEPROP 1 LAST PACK_TYPE 0402V
J 0
(2750 4975);
DISPLAY 0.617021 (2750 4975);
PAINT SKYBLUE (2750 4975);
FORCEPROP 1 LAST MATERIAL X7R
J 0
(2750 5075);
DISPLAY 0.617021 (2750 5075);
PAINT SKYBLUE (2750 5075);
FORCEPROP 2 LAST CDS_LOCATION C25W68
J 0
(2750 5275);
DISPLAY 0.617021 (2750 5275);
PAINT AQUA (2750 5275);
DISPLAY INVISIBLE (2750 5275);
FORCEPROP 1 LAST PATH I128
J 0
(2750 5325);
DISPLAY 0.978723 (2750 5325);
PAINT WHITE (2750 5325);
DISPLAY INVISIBLE (2750 5325);
FORCEPROP 2 LAST CDS_LIB dev_discrete
J 0
(2700 5175);
PAINT ORANGE (2700 5175);
DISPLAY INVISIBLE (2700 5175);
FORCEPROP 2 LAST CDS_SEC 1
J 0
(2750 5325);
PAINT ORANGE (2750 5325);
DISPLAY INVISIBLE (2750 5325);
FORCEPROP 2 LAST ROOM VDDQ_KLM_PWR_VR
J 0
(2750 5325);
DISPLAY 1.361702 (2750 5325);
PAINT ORANGE (2750 5325);
DISPLAY INVISIBLE (2750 5325);
FORCEPROP 2 LAST SEC_TYPE 0402V
J 0
(2750 5400);
DISPLAY 1.021277 (2750 5400);
PAINT ORANGE (2750 5400);
DISPLAY INVISIBLE (2750 5400);
FORCEPROP 2 LAST SEC 1
J 0
(2750 5400);
DISPLAY 0.680851 (2750 5400);
PAINT MONO (2750 5400);
DISPLAY INVISIBLE (2750 5400);
FORCEADD CAP..1
(150 5400);
FORCEPROP 1 LAST PART_NUMBER E15431-001
J 0
(200 5250);
DISPLAY 0.617021 (200 5250);
PAINT BLUE (200 5250);
FORCEPROP 1 LAST PACK_TYPE 0603LF
J 0
(200 5200);
DISPLAY 0.617021 (200 5200);
PAINT SKYBLUE (200 5200);
FORCEPROP 1 LAST LOCATION C25W29
J 0
(200 5500);
DISPLAY 0.617021 (200 5500);
PAINT AQUA (200 5500);
FORCEPROP 1 LAST VALUE 10UF
J 0
(200 5450);
DISPLAY 0.617021 (200 5450);
PAINT SKYBLUE (200 5450);
FORCEPROP 1 LAST MATERIAL X6S
J 0
(200 5300);
DISPLAY 0.617021 (200 5300);
PAINT SKYBLUE (200 5300);
FORCEPROP 1 LAST TOLERANCE 20%
J 0
(200 5350);
DISPLAY 0.617021 (200 5350);
PAINT SKYBLUE (200 5350);
FORCEPROP 1 LAST VOLTAGE 4V
J 0
(200 5400);
DISPLAY 0.617021 (200 5400);
PAINT SKYBLUE (200 5400);
FORCEPROP 1 LASTPIN (150 5300) $PN 2
J 0
(160 5280);
DISPLAY 0.617021 (160 5280);
PAINT ORANGE (160 5280);
FORCEPROP 1 LASTPIN (150 5500) $PN 1
J 0
(160 5480);
DISPLAY 0.617021 (160 5480);
PAINT ORANGE (160 5480);
FORCEPROP 1 LAST PATH I129
J 0
(200 5550);
DISPLAY 0.978723 (200 5550);
PAINT WHITE (200 5550);
DISPLAY INVISIBLE (200 5550);
FORCEPROP 2 LAST CDS_LIB mstr_discrete
J 0
(150 5400);
PAINT ORANGE (150 5400);
DISPLAY INVISIBLE (150 5400);
FORCEPROP 2 LAST SEC_TYPE 0603LF
J 0
(200 5600);
DISPLAY 1.021277 (200 5600);
PAINT ORANGE (200 5600);
DISPLAY INVISIBLE (200 5600);
FORCEPROP 2 LAST BOM_COST PROC_SOCKET
J 0
(200 5600);
DISPLAY 1.021277 (200 5600);
PAINT ORANGE (200 5600);
DISPLAY INVISIBLE (200 5600);
FORCEPROP 0 LAST SEC 1
J 0
(200 5550);
PAINT ORANGE (200 5550);
DISPLAY INVISIBLE (200 5550);
FORCEPROP 2 LAST ROOM CPU0
J 0
(200 5550);
DISPLAY 1.021277 (200 5550);
PAINT ORANGE (200 5550);
DISPLAY INVISIBLE (200 5550);
FORCEPROP 2 LAST CDS_LOCATION C25W29
J 0
(200 5500);
DISPLAY 0.617021 (200 5500);
PAINT AQUA (200 5500);
DISPLAY INVISIBLE (200 5500);
FORCEADD CAP..1
(-1450 1825);
FORCEPROP 1 LAST LOCATION C25W57
J 0
(-1400 1900);
DISPLAY 0.617021 (-1400 1900);
PAINT AQUA (-1400 1900);
FORCEPROP 1 LAST MATERIAL COG
J 0
(-1400 1700);
DISPLAY 0.617021 (-1400 1700);
PAINT SKYBLUE (-1400 1700);
FORCEPROP 1 LAST PART_NUMBER A36095-026
J 0
(-1400 1950);
DISPLAY 0.617021 (-1400 1950);
PAINT BLUE (-1400 1950);
FORCEPROP 1 LASTPIN (-1450 1925) $PN 1
J 0
(-1440 1905);
DISPLAY 0.787234 (-1440 1905);
PAINT ORANGE (-1440 1905);
FORCEPROP 1 LASTPIN (-1450 1725) $PN 2
J 0
(-1440 1705);
DISPLAY 0.787234 (-1440 1705);
PAINT ORANGE (-1440 1705);
FORCEPROP 1 LAST VALUE 100.0PF
J 0
(-1400 1850);
DISPLAY 0.617021 (-1400 1850);
PAINT SKYBLUE (-1400 1850);
FORCEPROP 1 LAST PACK_TYPE 0402LF
J 0
(-1400 1650);
DISPLAY 0.617021 (-1400 1650);
PAINT SKYBLUE (-1400 1650);
FORCEPROP 1 LAST VOLTAGE 50V
J 0
(-1400 1800);
DISPLAY 0.617021 (-1400 1800);
PAINT SKYBLUE (-1400 1800);
FORCEPROP 1 LAST TOLERANCE 5%
J 0
(-1400 1750);
DISPLAY 0.617021 (-1400 1750);
PAINT SKYBLUE (-1400 1750);
FORCEPROP 1 LAST PATH I130
J 0
(-1400 1975);
DISPLAY 0.978723 (-1400 1975);
PAINT WHITE (-1400 1975);
DISPLAY INVISIBLE (-1400 1975);
FORCEPROP 2 LAST SEC_TYPE 0402LF
J 0
(-1400 2025);
DISPLAY 1.021277 (-1400 2025);
PAINT ORANGE (-1400 2025);
DISPLAY INVISIBLE (-1400 2025);
FORCEPROP 0 LAST SEC 1
J 0
(-1400 2000);
PAINT MONO (-1400 2000);
DISPLAY INVISIBLE (-1400 2000);
FORCEPROP 0 LAST BOM_COST SM_CONTROLLER
J 0
(-1400 2025);
DISPLAY 1.021277 (-1400 2025);
PAINT ORANGE (-1400 2025);
DISPLAY INVISIBLE (-1400 2025);
FORCEPROP 0 LAST ROOM BMC
J 0
(-1400 1975);
DISPLAY 1.021277 (-1400 1975);
PAINT ORANGE (-1400 1975);
DISPLAY INVISIBLE (-1400 1975);
FORCEPROP 2 LAST CDS_LIB mstr_discrete
J 0
(-1450 1825);
PAINT MONO (-1450 1825);
DISPLAY INVISIBLE (-1450 1825);
FORCEPROP 0 LAST CDS_LOCATION C25W57
J 0
(-1400 2000);
PAINT MONO (-1400 2000);
DISPLAY INVISIBLE (-1400 2000);
FORCEADD P3V3_STBY..1
(3800 5650);
FORCEPROP 3 LASTPIN (3800 5600) SIG_NAME P3V3_STBY\g
J 0
(3810 5610);
DISPLAY 0.659574 (3810 5610);
PAINT MONO (3810 5610);
DISPLAY INVISIBLE (3810 5610);
FORCEPROP 1 LAST PATH I14
J 0
(3845 5652);
DISPLAY 0.340426 (3845 5652);
PAINT GREEN (3845 5652);
DISPLAY INVISIBLE (3845 5652);
FORCEPROP 1 LAST VOLTAGE 3.3V
J 0
(3755 5607);
DISPLAY 0.340426 (3755 5607);
PAINT GREEN (3755 5607);
DISPLAY INVISIBLE (3755 5607);
FORCEPROP 1 LAST HDL_POWER P3V3_STBY
J 0
(3500 5525);
DISPLAY 0.872340 (3500 5525);
PAINT ORANGE (3500 5525);
DISPLAY INVISIBLE (3500 5525);
FORCEPROP 1 LAST BODY_TYPE PLUMBING
J 0
(3755 5607);
DISPLAY 0.340426 (3755 5607);
PAINT GREEN (3755 5607);
DISPLAY INVISIBLE (3755 5607);
FORCEPROP 1 LAST SIZE 1B
J 0
(3845 5672);
DISPLAY 0.340426 (3845 5672);
PAINT GREEN (3845 5672);
DISPLAY INVISIBLE (3845 5672);
FORCEPROP 2 LAST CDS_LIB mstr_symbols
J 0
(3800 5650);
PAINT MONO (3800 5650);
DISPLAY INVISIBLE (3800 5650);
FORCEADD W_VCC_CIRCLE..1
(3100 5650);
FORCEPROP 3 LASTPIN (3100 5650) SIG_NAME VCC_VA_3V3\g
J 0
(3110 5660);
DISPLAY 0.659574 (3110 5660);
PAINT MONO (3110 5660);
DISPLAY INVISIBLE (3110 5660);
FORCEPROP 1 LAST HDL_POWER VCC_VA_3V3
J 1
(3121 5725);
DISPLAY 0.872340 (3121 5725);
PAINT ORANGE (3121 5725);
FORCEPROP 1 LAST PATH I16
J 0
(3100 5650);
DISPLAY 0.617021 (3100 5650);
PAINT GREEN (3100 5650);
DISPLAY INVISIBLE (3100 5650);
FORCEPROP 1 LAST BODY_TYPE PLUMBING
J 0
(3112 5644);
DISPLAY 0.340426 (3112 5644);
PAINT GREEN (3112 5644);
DISPLAY INVISIBLE (3112 5644);
FORCEPROP 2 LAST CDS_LIB w_power
J 0
(3100 5650);
PAINT MONO (3100 5650);
DISPLAY INVISIBLE (3100 5650);
FORCEPROP 1 LAST CDS_LMAN_SYM_OUTLINE -100,100,100,-100
J 0
(3100 5650);
DISPLAY 0.468085 (3100 5650);
PAINT GREEN (3100 5650);
DISPLAY INVISIBLE (3100 5650);
FORCEADD CAP..1
(3100 5175);
FORCEPROP 1 LAST PART_NUMBER E15431-003
J 0
(3150 5000);
DISPLAY 0.638298 (3150 5000);
PAINT BLUE (3150 5000);
FORCEPROP 1 LAST PACK_TYPE 0603
J 0
(3150 5050);
DISPLAY 0.638298 (3150 5050);
PAINT SKYBLUE (3150 5050);
FORCEPROP 1 LAST MATERIAL X6S
J 0
(3150 5100);
DISPLAY 0.638298 (3150 5100);
PAINT SKYBLUE (3150 5100);
FORCEPROP 1 LAST LOCATION C25W69
J 0
(3150 5300);
DISPLAY 0.638298 (3150 5300);
PAINT SKYBLUE (3150 5300);
FORCEPROP 1 LAST VALUE 4.7UF
J 0
(3150 5250);
DISPLAY 0.638298 (3150 5250);
PAINT SKYBLUE (3150 5250);
FORCEPROP 1 LAST VOLTAGE 6.3V
J 0
(3150 5200);
DISPLAY 0.638298 (3150 5200);
PAINT SKYBLUE (3150 5200);
FORCEPROP 1 LAST TOLERANCE 10%
J 0
(3150 5150);
DISPLAY 0.638298 (3150 5150);
PAINT SKYBLUE (3150 5150);
FORCEPROP 1 LAST PATH I17
J 0
(3150 5325);
DISPLAY 0.978723 (3150 5325);
PAINT WHITE (3150 5325);
DISPLAY INVISIBLE (3150 5325);
FORCEPROP 0 LAST CDS_SEC 1
J 0
(3150 5350);
PAINT MONO (3150 5350);
DISPLAY INVISIBLE (3150 5350);
FORCEPROP 0 LAST $SEC 1
J 0
(3150 5350);
PAINT MONO (3150 5350);
DISPLAY INVISIBLE (3150 5350);
FORCEPROP 0 LAST CDS_LOCATION C25W69
J 0
(3150 5350);
PAINT MONO (3150 5350);
DISPLAY INVISIBLE (3150 5350);
FORCEPROP 1 LASTPIN (3100 5275) $PN 1
J 0
(3110 5255);
DISPLAY 0.787234 (3110 5255);
PAINT ORANGE (3110 5255);
DISPLAY INVISIBLE (3110 5255);
FORCEPROP 1 LASTPIN (3100 5075) $PN 2
J 0
(3110 5055);
DISPLAY 0.787234 (3110 5055);
PAINT ORANGE (3110 5055);
DISPLAY INVISIBLE (3110 5055);
FORCEPROP 2 LAST CDS_LIB mstr_discrete
J 0
(3100 5175);
PAINT MONO (3100 5175);
DISPLAY INVISIBLE (3100 5175);
FORCEADD GND..1
(3100 4700);
FORCEPROP 3 LASTPIN (3100 4750) SIG_NAME GND\g
J 0
(3110 4760);
DISPLAY 0.659574 (3110 4760);
PAINT MONO (3110 4760);
DISPLAY INVISIBLE (3110 4760);
FORCEPROP 1 LAST PATH I18
J 0
(3175 4700);
DISPLAY 0.872340 (3175 4700);
PAINT AQUA (3175 4700);
DISPLAY INVISIBLE (3175 4700);
FORCEPROP 1 LAST HDL_POWER GND
J 0
(3100 4850);
DISPLAY 0.872340 (3100 4850);
PAINT GREEN (3100 4850);
DISPLAY INVISIBLE (3100 4850);
FORCEPROP 1 LAST SIZE 1B
J 0
(3175 4650);
DISPLAY 0.872340 (3175 4650);
PAINT AQUA (3175 4650);
DISPLAY INVISIBLE (3175 4650);
FORCEPROP 2 LAST CDS_LIB mstr_symbols
J 0
(3100 4700);
PAINT MONO (3100 4700);
DISPLAY INVISIBLE (3100 4700);
FORCEPROP 1 LAST BODY_TYPE PLUMBING
J 0
(3055 4657);
DISPLAY 0.340426 (3055 4657);
PAINT GREEN (3055 4657);
DISPLAY INVISIBLE (3055 4657);
FORCEPROP 1 LAST VOLTAGE 0.0V
J 0
(3055 4657);
DISPLAY 0.340426 (3055 4657);
PAINT GREEN (3055 4657);
DISPLAY INVISIBLE (3055 4657);
FORCEADD W_VCC_CIRCLE..1
(4800 5600);
FORCEPROP 3 LASTPIN (4800 5600) SIG_NAME P3V3_USB2A_ALG\g
J 0
(4810 5610);
DISPLAY 0.659574 (4810 5610);
PAINT MONO (4810 5610);
DISPLAY INVISIBLE (4810 5610);
FORCEPROP 1 LAST HDL_POWER P3V3_USB2A_ALG
J 1
(4821 5675);
DISPLAY 0.872340 (4821 5675);
PAINT ORANGE (4821 5675);
FORCEPROP 1 LAST PATH I2
J 0
(4800 5600);
DISPLAY 0.617021 (4800 5600);
PAINT GREEN (4800 5600);
DISPLAY INVISIBLE (4800 5600);
FORCEPROP 1 LAST BODY_TYPE PLUMBING
J 0
(4812 5594);
DISPLAY 0.340426 (4812 5594);
PAINT GREEN (4812 5594);
DISPLAY INVISIBLE (4812 5594);
FORCEPROP 1 LAST CDS_LMAN_SYM_OUTLINE -100,100,100,-100
J 0
(4800 5600);
DISPLAY 0.468085 (4800 5600);
PAINT GREEN (4800 5600);
DISPLAY INVISIBLE (4800 5600);
FORCEPROP 2 LAST CDS_LIB w_power
J 0
(4800 5600);
PAINT MONO (4800 5600);
DISPLAY INVISIBLE (4800 5600);
FORCEADD HCB1608KF-800T30-GP..1
R 1
(1500 5500);
FORCEPROP 0 LASTPIN (1350 5500) $PN 1
J 2
(1340 5510);
DISPLAY 0.808511 (1340 5510);
PAINT MONO (1340 5510);
FORCEPROP 1 LAST LOCATION FB2T1
J 0
(1425 5550);
DISPLAY 0.617021 (1425 5550);
PAINT GREEN (1425 5550);
FORCEPROP 0 LASTPIN (1650 5500) $PN 2
J 0
(1660 5510);
DISPLAY 0.808511 (1660 5510);
PAINT MONO (1660 5510);
FORCEPROP 1 LAST VALUE HCB1608KF-800T30-GP
J 0
(1400 5425);
DISPLAY 0.617021 (1400 5425);
PAINT GREEN (1400 5425);
FORCEPROP 2 LAST ATTRIBUTE 80OHM@100MHZ
J 0
(1400 5375);
DISPLAY 0.638298 (1400 5375);
PAINT GREEN (1400 5375);
FORCEPROP 2 LAST PACK_SIZE DCR=4MOHM
J 0
(1400 5275);
DISPLAY 0.638298 (1400 5275);
PAINT GREEN (1400 5275);
FORCEPROP 2 LAST RATED 3A
J 0
(1400 5325);
DISPLAY 0.638298 (1400 5325);
PAINT GREEN (1400 5325);
FORCEPROP 1 LAST PATH I22
R 1
J 0
(1500 5500);
DISPLAY 0.617021 (1500 5500);
PAINT GREEN (1500 5500);
DISPLAY INVISIBLE (1500 5500);
FORCEPROP 0 LAST CDS_SEC 1
R 1
J 0
(1425 5600);
PAINT MONO (1425 5600);
DISPLAY INVISIBLE (1425 5600);
FORCEPROP 0 LAST $SEC 1
R 1
J 0
(1425 5600);
PAINT MONO (1425 5600);
DISPLAY INVISIBLE (1425 5600);
FORCEPROP 0 LAST CDS_LOCATION FB2T1
R 1
J 0
(1425 5600);
PAINT MONO (1425 5600);
DISPLAY INVISIBLE (1425 5600);
FORCEPROP 1 LAST PACK_TYPE DISCRET-G9
R 1
J 0
(1500 5500);
DISPLAY 0.617021 (1500 5500);
PAINT GREEN (1500 5500);
DISPLAY INVISIBLE (1500 5500);
FORCEPROP 1 LAST PART_NUMBER 68.00230.231
R 1
J 0
(1500 5500);
DISPLAY 0.617021 (1500 5500);
PAINT GREEN (1500 5500);
DISPLAY INVISIBLE (1500 5500);
FORCEPROP 1 LAST CDS_LMAN_SYM_OUTLINE -50,100,50,-100
R 1
J 0
(1500 5500);
DISPLAY 0.468085 (1500 5500);
PAINT GREEN (1500 5500);
DISPLAY INVISIBLE (1500 5500);
FORCEPROP 2 LAST CDS_LIB w_hdl
J 0
(1500 5500);
PAINT MONO (1500 5500);
DISPLAY INVISIBLE (1500 5500);
FORCEADD P3V3_STBY..1
(1200 5650);
FORCEPROP 3 LASTPIN (1200 5600) SIG_NAME P3V3_STBY\g
J 0
(1210 5610);
DISPLAY 0.659574 (1210 5610);
PAINT MONO (1210 5610);
DISPLAY INVISIBLE (1210 5610);
FORCEPROP 1 LAST PATH I23
J 0
(1245 5652);
DISPLAY 0.340426 (1245 5652);
PAINT GREEN (1245 5652);
DISPLAY INVISIBLE (1245 5652);
FORCEPROP 1 LAST VOLTAGE 3.3V
J 0
(1155 5607);
DISPLAY 0.340426 (1155 5607);
PAINT GREEN (1155 5607);
DISPLAY INVISIBLE (1155 5607);
FORCEPROP 2 LAST CDS_LIB mstr_symbols
J 0
(1200 5650);
PAINT MONO (1200 5650);
DISPLAY INVISIBLE (1200 5650);
FORCEPROP 1 LAST HDL_POWER P3V3_STBY
J 0
(900 5525);
DISPLAY 0.872340 (900 5525);
PAINT ORANGE (900 5525);
DISPLAY INVISIBLE (900 5525);
FORCEPROP 1 LAST BODY_TYPE PLUMBING
J 0
(1155 5607);
DISPLAY 0.340426 (1155 5607);
PAINT GREEN (1155 5607);
DISPLAY INVISIBLE (1155 5607);
FORCEPROP 1 LAST SIZE 1B
J 0
(1245 5672);
DISPLAY 0.340426 (1245 5672);
PAINT GREEN (1245 5672);
DISPLAY INVISIBLE (1245 5672);
FORCEADD GND..1
(550 5075);
FORCEPROP 3 LASTPIN (550 5125) SIG_NAME GND\g
J 0
(560 5135);
DISPLAY 0.659574 (560 5135);
PAINT MONO (560 5135);
DISPLAY INVISIBLE (560 5135);
FORCEPROP 1 LAST PATH I24
J 0
(625 5075);
DISPLAY 0.872340 (625 5075);
PAINT AQUA (625 5075);
DISPLAY INVISIBLE (625 5075);
FORCEPROP 2 LAST CDS_LIB mstr_symbols
J 0
(550 5075);
PAINT ORANGE (550 5075);
DISPLAY INVISIBLE (550 5075);
FORCEPROP 1 LAST SIZE 1B
J 0
(625 5025);
DISPLAY 0.872340 (625 5025);
PAINT AQUA (625 5025);
DISPLAY INVISIBLE (625 5025);
FORCEPROP 1 LAST HDL_POWER GND
J 0
(550 5225);
DISPLAY 0.872340 (550 5225);
PAINT GREEN (550 5225);
DISPLAY INVISIBLE (550 5225);
FORCEPROP 1 LAST BODY_TYPE PLUMBING
J 0
(505 5032);
DISPLAY 0.340426 (505 5032);
PAINT GREEN (505 5032);
DISPLAY INVISIBLE (505 5032);
FORCEPROP 1 LAST VOLTAGE 0.0V
J 0
(505 5032);
DISPLAY 0.340426 (505 5032);
PAINT GREEN (505 5032);
DISPLAY INVISIBLE (505 5032);
FORCEADD CAP..1
(3725 3975);
FORCEPROP 1 LAST VOLTAGE 6.3V
J 0
(3775 4000);
DISPLAY 0.638298 (3775 4000);
PAINT SKYBLUE (3775 4000);
FORCEPROP 1 LAST MATERIAL X6S
J 0
(3775 3900);
DISPLAY 0.638298 (3775 3900);
PAINT SKYBLUE (3775 3900);
FORCEPROP 1 LAST PACK_TYPE 0603
J 0
(3775 3850);
DISPLAY 0.638298 (3775 3850);
PAINT SKYBLUE (3775 3850);
FORCEPROP 1 LAST TOLERANCE 10%
J 0
(3775 3950);
DISPLAY 0.638298 (3775 3950);
PAINT SKYBLUE (3775 3950);
FORCEPROP 1 LAST PART_NUMBER E15431-003
J 0
(3775 3800);
DISPLAY 0.638298 (3775 3800);
PAINT BLUE (3775 3800);
FORCEPROP 1 LAST LOCATION C25W39
J 0
(3775 4100);
DISPLAY 0.638298 (3775 4100);
PAINT SKYBLUE (3775 4100);
FORCEPROP 1 LAST VALUE 4.7UF
J 0
(3775 4050);
DISPLAY 0.638298 (3775 4050);
PAINT SKYBLUE (3775 4050);
FORCEPROP 1 LAST PATH I25
J 0
(3775 4125);
DISPLAY 0.978723 (3775 4125);
PAINT WHITE (3775 4125);
DISPLAY INVISIBLE (3775 4125);
FORCEPROP 0 LAST CDS_SEC 1
J 0
(3775 4150);
PAINT MONO (3775 4150);
DISPLAY INVISIBLE (3775 4150);
FORCEPROP 0 LAST $SEC 1
J 0
(3775 4150);
PAINT MONO (3775 4150);
DISPLAY INVISIBLE (3775 4150);
FORCEPROP 0 LAST CDS_LOCATION C25W39
J 0
(3775 4150);
PAINT MONO (3775 4150);
DISPLAY INVISIBLE (3775 4150);
FORCEPROP 1 LASTPIN (3725 4075) $PN 1
J 0
(3735 4055);
DISPLAY 0.787234 (3735 4055);
PAINT ORANGE (3735 4055);
DISPLAY INVISIBLE (3735 4055);
FORCEPROP 1 LASTPIN (3725 3875) $PN 2
J 0
(3735 3855);
DISPLAY 0.787234 (3735 3855);
PAINT ORANGE (3735 3855);
DISPLAY INVISIBLE (3735 3855);
FORCEPROP 2 LAST CDS_LIB mstr_discrete
J 0
(3725 3975);
PAINT MONO (3725 3975);
DISPLAY INVISIBLE (3725 3975);
FORCEADD W_VCC_CIRCLE..1
(3725 4450);
FORCEPROP 3 LASTPIN (3725 4450) SIG_NAME VCC_A_1V1\g
J 0
(3735 4460);
DISPLAY 0.659574 (3735 4460);
PAINT MONO (3735 4460);
DISPLAY INVISIBLE (3735 4460);
FORCEPROP 1 LAST HDL_POWER VCC_A_1V1
J 1
(3746 4525);
DISPLAY 0.872340 (3746 4525);
PAINT ORANGE (3746 4525);
FORCEPROP 1 LAST PATH I26
J 0
(3725 4450);
DISPLAY 0.617021 (3725 4450);
PAINT GREEN (3725 4450);
DISPLAY INVISIBLE (3725 4450);
FORCEPROP 1 LAST CDS_LMAN_SYM_OUTLINE -100,100,100,-100
J 0
(3725 4450);
DISPLAY 0.468085 (3725 4450);
PAINT GREEN (3725 4450);
DISPLAY INVISIBLE (3725 4450);
FORCEPROP 2 LAST CDS_LIB w_power
J 0
(3725 4450);
PAINT MONO (3725 4450);
DISPLAY INVISIBLE (3725 4450);
FORCEPROP 1 LAST BODY_TYPE PLUMBING
J 0
(3737 4444);
DISPLAY 0.340426 (3737 4444);
PAINT GREEN (3737 4444);
DISPLAY INVISIBLE (3737 4444);
FORCEADD GND..1
(3725 3600);
FORCEPROP 3 LASTPIN (3725 3650) SIG_NAME GND\g
J 0
(3735 3660);
DISPLAY 0.659574 (3735 3660);
PAINT MONO (3735 3660);
DISPLAY INVISIBLE (3735 3660);
FORCEPROP 1 LAST PATH I27
J 0
(3800 3600);
DISPLAY 0.872340 (3800 3600);
PAINT AQUA (3800 3600);
DISPLAY INVISIBLE (3800 3600);
FORCEPROP 1 LAST VOLTAGE 0.0V
J 0
(3680 3557);
DISPLAY 0.340426 (3680 3557);
PAINT GREEN (3680 3557);
DISPLAY INVISIBLE (3680 3557);
FORCEPROP 1 LAST BODY_TYPE PLUMBING
J 0
(3680 3557);
DISPLAY 0.340426 (3680 3557);
PAINT GREEN (3680 3557);
DISPLAY INVISIBLE (3680 3557);
FORCEPROP 2 LAST CDS_LIB mstr_symbols
J 0
(3725 3600);
PAINT MONO (3725 3600);
DISPLAY INVISIBLE (3725 3600);
FORCEPROP 1 LAST SIZE 1B
J 0
(3800 3550);
DISPLAY 0.872340 (3800 3550);
PAINT AQUA (3800 3550);
DISPLAY INVISIBLE (3800 3550);
FORCEPROP 1 LAST HDL_POWER GND
J 0
(3725 3750);
DISPLAY 0.872340 (3725 3750);
PAINT GREEN (3725 3750);
DISPLAY INVISIBLE (3725 3750);
FORCEADD W_VCC_CIRCLE..1
(3950 3350);
FORCEPROP 3 LASTPIN (3950 3350) SIG_NAME P1V2_AUX_BMC\g
J 0
(3960 3360);
DISPLAY 0.659574 (3960 3360);
PAINT MONO (3960 3360);
DISPLAY INVISIBLE (3960 3360);
FORCEPROP 1 LAST HDL_POWER P1V2_AUX_BMC
J 1
(3971 3425);
DISPLAY 0.872340 (3971 3425);
PAINT ORANGE (3971 3425);
FORCEPROP 1 LAST PATH I29
J 0
(3950 3350);
DISPLAY 0.617021 (3950 3350);
PAINT GREEN (3950 3350);
DISPLAY INVISIBLE (3950 3350);
FORCEPROP 1 LAST BODY_TYPE PLUMBING
J 0
(3962 3344);
DISPLAY 0.340426 (3962 3344);
PAINT GREEN (3962 3344);
DISPLAY INVISIBLE (3962 3344);
FORCEPROP 1 LAST CDS_LMAN_SYM_OUTLINE -100,100,100,-100
J 0
(3950 3350);
DISPLAY 0.468085 (3950 3350);
PAINT GREEN (3950 3350);
DISPLAY INVISIBLE (3950 3350);
FORCEPROP 2 LAST CDS_LIB w_power
J 0
(3950 3350);
PAINT MONO (3950 3350);
DISPLAY INVISIBLE (3950 3350);
FORCEADD CAP..1
(3275 3000);
FORCEPROP 1 LAST LOCATION C25W50
J 0
(3325 3125);
DISPLAY 0.638298 (3325 3125);
PAINT SKYBLUE (3325 3125);
FORCEPROP 1 LAST PART_NUMBER E15431-003
J 0
(3325 2825);
DISPLAY 0.638298 (3325 2825);
PAINT BLUE (3325 2825);
FORCEPROP 1 LAST PACK_TYPE 0603
J 0
(3325 2875);
DISPLAY 0.638298 (3325 2875);
PAINT SKYBLUE (3325 2875);
FORCEPROP 1 LAST MATERIAL X6S
J 0
(3325 2925);
DISPLAY 0.638298 (3325 2925);
PAINT SKYBLUE (3325 2925);
FORCEPROP 1 LAST TOLERANCE 10%
J 0
(3325 2975);
DISPLAY 0.638298 (3325 2975);
PAINT SKYBLUE (3325 2975);
FORCEPROP 1 LAST VOLTAGE 6.3V
J 0
(3325 3025);
DISPLAY 0.638298 (3325 3025);
PAINT SKYBLUE (3325 3025);
FORCEPROP 1 LAST VALUE 4.7UF
J 0
(3325 3075);
DISPLAY 0.638298 (3325 3075);
PAINT SKYBLUE (3325 3075);
FORCEPROP 1 LAST PATH I31
J 0
(3325 3150);
DISPLAY 0.978723 (3325 3150);
PAINT WHITE (3325 3150);
DISPLAY INVISIBLE (3325 3150);
FORCEPROP 0 LAST CDS_SEC 1
J 0
(3325 3175);
PAINT MONO (3325 3175);
DISPLAY INVISIBLE (3325 3175);
FORCEPROP 0 LAST $SEC 1
J 0
(3325 3175);
PAINT MONO (3325 3175);
DISPLAY INVISIBLE (3325 3175);
FORCEPROP 0 LAST CDS_LOCATION C25W50
J 0
(3325 3175);
PAINT MONO (3325 3175);
DISPLAY INVISIBLE (3325 3175);
FORCEPROP 1 LASTPIN (3275 3100) $PN 1
J 0
(3285 3080);
DISPLAY 0.787234 (3285 3080);
PAINT ORANGE (3285 3080);
DISPLAY INVISIBLE (3285 3080);
FORCEPROP 1 LASTPIN (3275 2900) $PN 2
J 0
(3285 2880);
DISPLAY 0.787234 (3285 2880);
PAINT ORANGE (3285 2880);
DISPLAY INVISIBLE (3285 2880);
FORCEPROP 2 LAST CDS_LIB mstr_discrete
J 0
(3275 3000);
PAINT MONO (3275 3000);
DISPLAY INVISIBLE (3275 3000);
FORCEADD GND..1
(3275 2625);
FORCEPROP 3 LASTPIN (3275 2675) SIG_NAME GND\g
J 0
(3285 2685);
DISPLAY 0.659574 (3285 2685);
PAINT MONO (3285 2685);
DISPLAY INVISIBLE (3285 2685);
FORCEPROP 1 LAST PATH I32
J 0
(3350 2625);
DISPLAY 0.872340 (3350 2625);
PAINT AQUA (3350 2625);
DISPLAY INVISIBLE (3350 2625);
FORCEPROP 1 LAST VOLTAGE 0.0V
J 0
(3230 2582);
DISPLAY 0.340426 (3230 2582);
PAINT GREEN (3230 2582);
DISPLAY INVISIBLE (3230 2582);
FORCEPROP 1 LAST BODY_TYPE PLUMBING
J 0
(3230 2582);
DISPLAY 0.340426 (3230 2582);
PAINT GREEN (3230 2582);
DISPLAY INVISIBLE (3230 2582);
FORCEPROP 1 LAST HDL_POWER GND
J 0
(3275 2775);
DISPLAY 0.872340 (3275 2775);
PAINT GREEN (3275 2775);
DISPLAY INVISIBLE (3275 2775);
FORCEPROP 1 LAST SIZE 1B
J 0
(3350 2575);
DISPLAY 0.872340 (3350 2575);
PAINT AQUA (3350 2575);
DISPLAY INVISIBLE (3350 2575);
FORCEPROP 2 LAST CDS_LIB mstr_symbols
J 0
(3275 2625);
PAINT MONO (3275 2625);
DISPLAY INVISIBLE (3275 2625);
FORCEADD GND..1
(4800 4900);
FORCEPROP 3 LASTPIN (4800 4950) SIG_NAME GND\g
J 0
(4810 4960);
DISPLAY 0.659574 (4810 4960);
PAINT MONO (4810 4960);
DISPLAY INVISIBLE (4810 4960);
FORCEPROP 1 LAST PATH I4
J 0
(4875 4900);
DISPLAY 0.872340 (4875 4900);
PAINT AQUA (4875 4900);
DISPLAY INVISIBLE (4875 4900);
FORCEPROP 1 LAST HDL_POWER GND
J 0
(4800 5050);
DISPLAY 0.872340 (4800 5050);
PAINT GREEN (4800 5050);
DISPLAY INVISIBLE (4800 5050);
FORCEPROP 1 LAST SIZE 1B
J 0
(4875 4850);
DISPLAY 0.872340 (4875 4850);
PAINT AQUA (4875 4850);
DISPLAY INVISIBLE (4875 4850);
FORCEPROP 1 LAST BODY_TYPE PLUMBING
J 0
(4755 4857);
DISPLAY 0.340426 (4755 4857);
PAINT GREEN (4755 4857);
DISPLAY INVISIBLE (4755 4857);
FORCEPROP 1 LAST VOLTAGE 0.0V
J 0
(4755 4857);
DISPLAY 0.340426 (4755 4857);
PAINT GREEN (4755 4857);
DISPLAY INVISIBLE (4755 4857);
FORCEPROP 2 LAST CDS_LIB mstr_symbols
J 0
(4800 4900);
PAINT MONO (4800 4900);
DISPLAY INVISIBLE (4800 4900);
FORCEADD CAP..1
(2425 1750);
FORCEPROP 1 LAST LOCATION C25W62
J 0
(2475 1875);
DISPLAY 0.638298 (2475 1875);
PAINT SKYBLUE (2475 1875);
FORCEPROP 1 LAST VALUE 4.7UF
J 0
(2475 1825);
DISPLAY 0.638298 (2475 1825);
PAINT SKYBLUE (2475 1825);
FORCEPROP 1 LAST VOLTAGE 6.3V
J 0
(2475 1775);
DISPLAY 0.638298 (2475 1775);
PAINT SKYBLUE (2475 1775);
FORCEPROP 1 LAST PART_NUMBER E15431-003
J 0
(2475 1575);
DISPLAY 0.638298 (2475 1575);
PAINT BLUE (2475 1575);
FORCEPROP 1 LAST PACK_TYPE 0603
J 0
(2475 1625);
DISPLAY 0.638298 (2475 1625);
PAINT SKYBLUE (2475 1625);
FORCEPROP 1 LAST MATERIAL X6S
J 0
(2475 1675);
DISPLAY 0.638298 (2475 1675);
PAINT SKYBLUE (2475 1675);
FORCEPROP 1 LAST TOLERANCE 10%
J 0
(2475 1725);
DISPLAY 0.638298 (2475 1725);
PAINT SKYBLUE (2475 1725);
FORCEPROP 1 LAST PATH I40
J 0
(2475 1900);
DISPLAY 0.978723 (2475 1900);
PAINT WHITE (2475 1900);
DISPLAY INVISIBLE (2475 1900);
FORCEPROP 0 LAST CDS_SEC 1
J 0
(2475 1925);
PAINT MONO (2475 1925);
DISPLAY INVISIBLE (2475 1925);
FORCEPROP 0 LAST $SEC 1
J 0
(2475 1925);
PAINT MONO (2475 1925);
DISPLAY INVISIBLE (2475 1925);
FORCEPROP 0 LAST CDS_LOCATION C25W62
J 0
(2475 1925);
PAINT MONO (2475 1925);
DISPLAY INVISIBLE (2475 1925);
FORCEPROP 1 LASTPIN (2425 1850) $PN 1
J 0
(2435 1830);
DISPLAY 0.787234 (2435 1830);
PAINT ORANGE (2435 1830);
DISPLAY INVISIBLE (2435 1830);
FORCEPROP 1 LASTPIN (2425 1650) $PN 2
J 0
(2435 1630);
DISPLAY 0.787234 (2435 1630);
PAINT ORANGE (2435 1630);
DISPLAY INVISIBLE (2435 1630);
FORCEPROP 2 LAST CDS_LIB mstr_discrete
J 0
(2425 1750);
PAINT MONO (2425 1750);
DISPLAY INVISIBLE (2425 1750);
FORCEADD GND..1
(2425 1375);
FORCEPROP 3 LASTPIN (2425 1425) SIG_NAME GND\g
J 0
(2435 1435);
DISPLAY 0.659574 (2435 1435);
PAINT MONO (2435 1435);
DISPLAY INVISIBLE (2435 1435);
FORCEPROP 1 LAST PATH I41
J 0
(2500 1375);
DISPLAY 0.872340 (2500 1375);
PAINT AQUA (2500 1375);
DISPLAY INVISIBLE (2500 1375);
FORCEPROP 1 LAST VOLTAGE 0.0V
J 0
(2380 1332);
DISPLAY 0.340426 (2380 1332);
PAINT GREEN (2380 1332);
DISPLAY INVISIBLE (2380 1332);
FORCEPROP 1 LAST BODY_TYPE PLUMBING
J 0
(2380 1332);
DISPLAY 0.340426 (2380 1332);
PAINT GREEN (2380 1332);
DISPLAY INVISIBLE (2380 1332);
FORCEPROP 2 LAST CDS_LIB mstr_symbols
J 0
(2425 1375);
PAINT MONO (2425 1375);
DISPLAY INVISIBLE (2425 1375);
FORCEPROP 1 LAST HDL_POWER GND
J 0
(2425 1525);
DISPLAY 0.872340 (2425 1525);
PAINT GREEN (2425 1525);
DISPLAY INVISIBLE (2425 1525);
FORCEPROP 1 LAST SIZE 1B
J 0
(2500 1325);
DISPLAY 0.872340 (2500 1325);
PAINT AQUA (2500 1325);
DISPLAY INVISIBLE (2500 1325);
FORCEADD HCB1608KF-800T30-GP..1
R 1
(2325 4300);
FORCEPROP 2 LAST RATED 3A
J 0
(2225 4125);
DISPLAY 0.638298 (2225 4125);
PAINT GREEN (2225 4125);
FORCEPROP 2 LAST ATTRIBUTE 80OHM@100MHZ
J 0
(2225 4175);
DISPLAY 0.638298 (2225 4175);
PAINT GREEN (2225 4175);
FORCEPROP 0 LASTPIN (2475 4300) $PN 2
J 0
(2485 4310);
DISPLAY 0.808511 (2485 4310);
PAINT MONO (2485 4310);
FORCEPROP 0 LASTPIN (2175 4300) $PN 1
J 2
(2165 4310);
DISPLAY 0.808511 (2165 4310);
PAINT MONO (2165 4310);
FORCEPROP 1 LAST LOCATION FB2T7
J 0
(2250 4350);
DISPLAY 0.617021 (2250 4350);
PAINT GREEN (2250 4350);
FORCEPROP 2 LAST PACK_SIZE DCR=4MOHM
J 0
(2225 4075);
DISPLAY 0.638298 (2225 4075);
PAINT GREEN (2225 4075);
FORCEPROP 1 LAST VALUE HCB1608KF-800T30-GP
J 0
(2225 4225);
DISPLAY 0.617021 (2225 4225);
PAINT GREEN (2225 4225);
FORCEPROP 1 LAST PATH I42
R 1
J 0
(2325 4300);
DISPLAY 0.617021 (2325 4300);
PAINT GREEN (2325 4300);
DISPLAY INVISIBLE (2325 4300);
FORCEPROP 0 LAST CDS_SEC 1
R 1
J 0
(2250 4400);
PAINT MONO (2250 4400);
DISPLAY INVISIBLE (2250 4400);
FORCEPROP 0 LAST $SEC 1
R 1
J 0
(2250 4400);
PAINT MONO (2250 4400);
DISPLAY INVISIBLE (2250 4400);
FORCEPROP 0 LAST CDS_LOCATION FB2T7
R 1
J 0
(2250 4400);
PAINT MONO (2250 4400);
DISPLAY INVISIBLE (2250 4400);
FORCEPROP 1 LAST PART_NUMBER 68.00230.231
R 1
J 0
(2325 4300);
DISPLAY 0.617021 (2325 4300);
PAINT GREEN (2325 4300);
DISPLAY INVISIBLE (2325 4300);
FORCEPROP 1 LAST PACK_TYPE DISCRET-G9
R 1
J 0
(2325 4300);
DISPLAY 0.617021 (2325 4300);
PAINT GREEN (2325 4300);
DISPLAY INVISIBLE (2325 4300);
FORCEPROP 1 LAST CDS_LMAN_SYM_OUTLINE -50,100,50,-100
R 1
J 0
(2325 4300);
DISPLAY 0.468085 (2325 4300);
PAINT GREEN (2325 4300);
DISPLAY INVISIBLE (2325 4300);
FORCEPROP 2 LAST CDS_LIB w_hdl
J 0
(2325 4300);
PAINT MONO (2325 4300);
DISPLAY INVISIBLE (2325 4300);
FORCEADD W_VCC_CIRCLE..1
(2025 4400);
FORCEPROP 3 LASTPIN (2025 4400) SIG_NAME P1V15_AUX_BMC\g
J 0
(2035 4410);
DISPLAY 0.659574 (2035 4410);
PAINT MONO (2035 4410);
DISPLAY INVISIBLE (2035 4410);
FORCEPROP 1 LAST HDL_POWER P1V15_AUX_BMC
J 1
(2046 4475);
DISPLAY 0.872340 (2046 4475);
PAINT ORANGE (2046 4475);
FORCEPROP 1 LAST PATH I43
J 0
(2025 4400);
DISPLAY 0.617021 (2025 4400);
PAINT GREEN (2025 4400);
DISPLAY INVISIBLE (2025 4400);
FORCEPROP 2 LAST CDS_LIB w_power
J 0
(2025 4400);
PAINT MONO (2025 4400);
DISPLAY INVISIBLE (2025 4400);
FORCEPROP 1 LAST CDS_LMAN_SYM_OUTLINE -100,100,100,-100
J 0
(2025 4400);
DISPLAY 0.468085 (2025 4400);
PAINT GREEN (2025 4400);
DISPLAY INVISIBLE (2025 4400);
FORCEPROP 1 LAST BODY_TYPE PLUMBING
J 0
(2037 4394);
DISPLAY 0.340426 (2037 4394);
PAINT GREEN (2037 4394);
DISPLAY INVISIBLE (2037 4394);
FORCEADD P3V3_STBY..1
(1575 3475);
FORCEPROP 3 LASTPIN (1575 3425) SIG_NAME P3V3_STBY\g
J 0
(1585 3435);
DISPLAY 0.659574 (1585 3435);
PAINT MONO (1585 3435);
DISPLAY INVISIBLE (1585 3435);
FORCEPROP 1 LAST PATH I44
J 0
(1620 3477);
DISPLAY 0.340426 (1620 3477);
PAINT GREEN (1620 3477);
DISPLAY INVISIBLE (1620 3477);
FORCEPROP 1 LAST VOLTAGE 3.3V
J 0
(1530 3432);
DISPLAY 0.340426 (1530 3432);
PAINT GREEN (1530 3432);
DISPLAY INVISIBLE (1530 3432);
FORCEPROP 1 LAST SIZE 1B
J 0
(1620 3497);
DISPLAY 0.340426 (1620 3497);
PAINT GREEN (1620 3497);
DISPLAY INVISIBLE (1620 3497);
FORCEPROP 1 LAST BODY_TYPE PLUMBING
J 0
(1530 3432);
DISPLAY 0.340426 (1530 3432);
PAINT GREEN (1530 3432);
DISPLAY INVISIBLE (1530 3432);
FORCEPROP 1 LAST HDL_POWER P3V3_STBY
J 0
(1275 3350);
DISPLAY 0.872340 (1275 3350);
PAINT ORANGE (1275 3350);
DISPLAY INVISIBLE (1275 3350);
FORCEPROP 2 LAST CDS_LIB mstr_symbols
J 0
(1575 3475);
PAINT MONO (1575 3475);
DISPLAY INVISIBLE (1575 3475);
FORCEADD W_VCC_CIRCLE..1
(1125 4450);
FORCEPROP 3 LASTPIN (1125 4450) SIG_NAME VCC_DACAV3V3\g
J 0
(1135 4460);
DISPLAY 0.659574 (1135 4460);
PAINT MONO (1135 4460);
DISPLAY INVISIBLE (1135 4460);
FORCEPROP 1 LAST HDL_POWER VCC_DACAV3V3
J 1
(1146 4525);
DISPLAY 0.872340 (1146 4525);
PAINT ORANGE (1146 4525);
FORCEPROP 1 LAST PATH I45
J 0
(1125 4450);
DISPLAY 0.617021 (1125 4450);
PAINT GREEN (1125 4450);
DISPLAY INVISIBLE (1125 4450);
FORCEPROP 1 LAST BODY_TYPE PLUMBING
J 0
(1137 4444);
DISPLAY 0.340426 (1137 4444);
PAINT GREEN (1137 4444);
DISPLAY INVISIBLE (1137 4444);
FORCEPROP 1 LAST CDS_LMAN_SYM_OUTLINE -100,100,100,-100
J 0
(1125 4450);
DISPLAY 0.468085 (1125 4450);
PAINT GREEN (1125 4450);
DISPLAY INVISIBLE (1125 4450);
FORCEPROP 2 LAST CDS_LIB w_power
J 0
(1125 4450);
PAINT MONO (1125 4450);
DISPLAY INVISIBLE (1125 4450);
FORCEADD CAP..1
(1125 4000);
FORCEPROP 1 LAST PART_NUMBER E15431-003
J 0
(1175 3825);
DISPLAY 0.638298 (1175 3825);
PAINT BLUE (1175 3825);
FORCEPROP 1 LAST LOCATION C25W36
J 0
(1175 4125);
DISPLAY 0.638298 (1175 4125);
PAINT SKYBLUE (1175 4125);
FORCEPROP 1 LAST VALUE 4.7UF
J 0
(1175 4075);
DISPLAY 0.638298 (1175 4075);
PAINT SKYBLUE (1175 4075);
FORCEPROP 1 LAST VOLTAGE 6.3V
J 0
(1175 4025);
DISPLAY 0.638298 (1175 4025);
PAINT SKYBLUE (1175 4025);
FORCEPROP 1 LAST TOLERANCE 10%
J 0
(1175 3975);
DISPLAY 0.638298 (1175 3975);
PAINT SKYBLUE (1175 3975);
FORCEPROP 1 LAST MATERIAL X6S
J 0
(1175 3925);
DISPLAY 0.638298 (1175 3925);
PAINT SKYBLUE (1175 3925);
FORCEPROP 1 LAST PACK_TYPE 0603
J 0
(1175 3875);
DISPLAY 0.638298 (1175 3875);
PAINT SKYBLUE (1175 3875);
FORCEPROP 1 LAST PATH I46
J 0
(1175 4150);
DISPLAY 0.978723 (1175 4150);
PAINT WHITE (1175 4150);
DISPLAY INVISIBLE (1175 4150);
FORCEPROP 0 LAST CDS_SEC 1
J 0
(1175 4175);
PAINT MONO (1175 4175);
DISPLAY INVISIBLE (1175 4175);
FORCEPROP 0 LAST $SEC 1
J 0
(1175 4175);
PAINT MONO (1175 4175);
DISPLAY INVISIBLE (1175 4175);
FORCEPROP 0 LAST CDS_LOCATION C25W36
J 0
(1175 4175);
PAINT MONO (1175 4175);
DISPLAY INVISIBLE (1175 4175);
FORCEPROP 1 LASTPIN (1125 4100) $PN 1
J 0
(1135 4080);
DISPLAY 0.787234 (1135 4080);
PAINT ORANGE (1135 4080);
DISPLAY INVISIBLE (1135 4080);
FORCEPROP 1 LASTPIN (1125 3900) $PN 2
J 0
(1135 3880);
DISPLAY 0.787234 (1135 3880);
PAINT ORANGE (1135 3880);
DISPLAY INVISIBLE (1135 3880);
FORCEPROP 2 LAST CDS_LIB mstr_discrete
J 0
(1125 4000);
PAINT MONO (1125 4000);
DISPLAY INVISIBLE (1125 4000);
FORCEADD GND..1
(1125 3475);
FORCEPROP 3 LASTPIN (1125 3525) SIG_NAME GND\g
J 0
(1135 3535);
DISPLAY 0.659574 (1135 3535);
PAINT MONO (1135 3535);
DISPLAY INVISIBLE (1135 3535);
FORCEPROP 1 LAST PATH I49
J 0
(1200 3475);
DISPLAY 0.872340 (1200 3475);
PAINT AQUA (1200 3475);
DISPLAY INVISIBLE (1200 3475);
FORCEPROP 1 LAST VOLTAGE 0.0V
J 0
(1080 3432);
DISPLAY 0.340426 (1080 3432);
PAINT GREEN (1080 3432);
DISPLAY INVISIBLE (1080 3432);
FORCEPROP 1 LAST BODY_TYPE PLUMBING
J 0
(1080 3432);
DISPLAY 0.340426 (1080 3432);
PAINT GREEN (1080 3432);
DISPLAY INVISIBLE (1080 3432);
FORCEPROP 2 LAST CDS_LIB mstr_symbols
J 0
(1125 3475);
PAINT MONO (1125 3475);
DISPLAY INVISIBLE (1125 3475);
FORCEPROP 1 LAST SIZE 1B
J 0
(1200 3425);
DISPLAY 0.872340 (1200 3425);
PAINT AQUA (1200 3425);
DISPLAY INVISIBLE (1200 3425);
FORCEPROP 1 LAST HDL_POWER GND
J 0
(1125 3625);
DISPLAY 0.872340 (1125 3625);
PAINT GREEN (1125 3625);
DISPLAY INVISIBLE (1125 3625);
FORCEADD CAP..1
(4300 5300);
FORCEPROP 1 LAST LOCATION C25W70
J 0
(4350 5425);
DISPLAY 0.638298 (4350 5425);
PAINT SKYBLUE (4350 5425);
FORCEPROP 1 LAST VALUE 4.7UF
J 0
(4350 5375);
DISPLAY 0.638298 (4350 5375);
PAINT SKYBLUE (4350 5375);
FORCEPROP 1 LAST VOLTAGE 6.3V
J 0
(4350 5325);
DISPLAY 0.638298 (4350 5325);
PAINT SKYBLUE (4350 5325);
FORCEPROP 1 LAST TOLERANCE 10%
J 0
(4350 5275);
DISPLAY 0.638298 (4350 5275);
PAINT SKYBLUE (4350 5275);
FORCEPROP 1 LAST MATERIAL X6S
J 0
(4350 5225);
DISPLAY 0.638298 (4350 5225);
PAINT SKYBLUE (4350 5225);
FORCEPROP 1 LAST PACK_TYPE 0603
J 0
(4350 5175);
DISPLAY 0.638298 (4350 5175);
PAINT SKYBLUE (4350 5175);
FORCEPROP 1 LAST PART_NUMBER E15431-003
J 0
(4350 5125);
DISPLAY 0.638298 (4350 5125);
PAINT BLUE (4350 5125);
FORCEPROP 1 LAST PATH I5
J 0
(4350 5450);
DISPLAY 0.978723 (4350 5450);
PAINT WHITE (4350 5450);
DISPLAY INVISIBLE (4350 5450);
FORCEPROP 0 LAST CDS_SEC 1
J 0
(4350 5475);
PAINT MONO (4350 5475);
DISPLAY INVISIBLE (4350 5475);
FORCEPROP 0 LAST $SEC 1
J 0
(4350 5475);
PAINT MONO (4350 5475);
DISPLAY INVISIBLE (4350 5475);
FORCEPROP 0 LAST CDS_LOCATION C25W70
J 0
(4350 5475);
PAINT MONO (4350 5475);
DISPLAY INVISIBLE (4350 5475);
FORCEPROP 1 LASTPIN (4300 5400) $PN 1
J 0
(4310 5380);
DISPLAY 0.787234 (4310 5380);
PAINT ORANGE (4310 5380);
DISPLAY INVISIBLE (4310 5380);
FORCEPROP 1 LASTPIN (4300 5200) $PN 2
J 0
(4310 5180);
DISPLAY 0.787234 (4310 5180);
PAINT ORANGE (4310 5180);
DISPLAY INVISIBLE (4310 5180);
FORCEPROP 2 LAST CDS_LIB mstr_discrete
J 0
(4300 5300);
PAINT MONO (4300 5300);
DISPLAY INVISIBLE (4300 5300);
FORCEADD CAP..1
(550 2900);
FORCEPROP 1 LAST VALUE 4.7UF
J 0
(600 2975);
DISPLAY 0.638298 (600 2975);
PAINT SKYBLUE (600 2975);
FORCEPROP 1 LAST VOLTAGE 6.3V
J 0
(600 2925);
DISPLAY 0.638298 (600 2925);
PAINT SKYBLUE (600 2925);
FORCEPROP 1 LAST TOLERANCE 10%
J 0
(600 2875);
DISPLAY 0.638298 (600 2875);
PAINT SKYBLUE (600 2875);
FORCEPROP 1 LAST LOCATION C25W47
J 0
(600 3025);
DISPLAY 0.638298 (600 3025);
PAINT SKYBLUE (600 3025);
FORCEPROP 1 LAST MATERIAL X6S
J 0
(600 2825);
DISPLAY 0.638298 (600 2825);
PAINT SKYBLUE (600 2825);
FORCEPROP 1 LAST PACK_TYPE 0603
J 0
(600 2775);
DISPLAY 0.638298 (600 2775);
PAINT SKYBLUE (600 2775);
FORCEPROP 1 LAST PART_NUMBER E15431-003
J 0
(600 2725);
DISPLAY 0.638298 (600 2725);
PAINT BLUE (600 2725);
FORCEPROP 1 LAST PATH I50
J 0
(600 3050);
DISPLAY 0.978723 (600 3050);
PAINT WHITE (600 3050);
DISPLAY INVISIBLE (600 3050);
FORCEPROP 0 LAST CDS_SEC 1
J 0
(600 3075);
PAINT MONO (600 3075);
DISPLAY INVISIBLE (600 3075);
FORCEPROP 0 LAST $SEC 1
J 0
(600 3075);
PAINT MONO (600 3075);
DISPLAY INVISIBLE (600 3075);
FORCEPROP 0 LAST CDS_LOCATION C25W47
J 0
(600 3075);
PAINT MONO (600 3075);
DISPLAY INVISIBLE (600 3075);
FORCEPROP 1 LASTPIN (550 3000) $PN 1
J 0
(560 2980);
DISPLAY 0.787234 (560 2980);
PAINT ORANGE (560 2980);
DISPLAY INVISIBLE (560 2980);
FORCEPROP 1 LASTPIN (550 2800) $PN 2
J 0
(560 2780);
DISPLAY 0.787234 (560 2780);
PAINT ORANGE (560 2780);
DISPLAY INVISIBLE (560 2780);
FORCEPROP 2 LAST CDS_LIB mstr_discrete
J 0
(550 2900);
PAINT MONO (550 2900);
DISPLAY INVISIBLE (550 2900);
FORCEADD CAP..1
(250 2900);
FORCEPROP 1 LAST LOCATION C25W46
J 0
(300 3000);
DISPLAY 0.617021 (300 3000);
PAINT AQUA (300 3000);
FORCEPROP 1 LAST PART_NUMBER C95333-007
J 0
(300 2750);
DISPLAY 0.617021 (300 2750);
PAINT BLUE (300 2750);
FORCEPROP 1 LAST PACK_TYPE 0805
J 0
(300 2700);
DISPLAY 0.617021 (300 2700);
PAINT SKYBLUE (300 2700);
FORCEPROP 1 LAST MATERIAL X6S
J 0
(300 2800);
DISPLAY 0.617021 (300 2800);
PAINT SKYBLUE (300 2800);
FORCEPROP 1 LAST TOLERANCE 10%
J 0
(300 2850);
DISPLAY 0.617021 (300 2850);
PAINT SKYBLUE (300 2850);
FORCEPROP 1 LAST VALUE 10UF
J 0
(300 2950);
DISPLAY 0.617021 (300 2950);
PAINT SKYBLUE (300 2950);
FORCEPROP 1 LAST VOLTAGE 16V
J 0
(300 2900);
DISPLAY 0.617021 (300 2900);
PAINT SKYBLUE (300 2900);
FORCEPROP 1 LAST PATH I51
J 0
(300 3050);
DISPLAY 0.978723 (300 3050);
PAINT WHITE (300 3050);
DISPLAY INVISIBLE (300 3050);
FORCEPROP 0 LAST CDS_SEC 1
J 0
(300 3050);
PAINT MONO (300 3050);
DISPLAY INVISIBLE (300 3050);
FORCEPROP 0 LAST $SEC 1
J 0
(300 3050);
PAINT MONO (300 3050);
DISPLAY INVISIBLE (300 3050);
FORCEPROP 0 LAST CDS_LOCATION C25W46
J 0
(300 3050);
PAINT MONO (300 3050);
DISPLAY INVISIBLE (300 3050);
FORCEPROP 0 LAST BOM_COST SM_CONTROLLER
J 0
(300 3100);
DISPLAY 1.021277 (300 3100);
PAINT ORANGE (300 3100);
DISPLAY INVISIBLE (300 3100);
FORCEPROP 0 LAST ROOM BMC
J 0
(300 3050);
DISPLAY 1.021277 (300 3050);
PAINT ORANGE (300 3050);
DISPLAY INVISIBLE (300 3050);
FORCEPROP 2 LAST CDS_LIB mstr_discrete
J 0
(250 2900);
PAINT MONO (250 2900);
DISPLAY INVISIBLE (250 2900);
FORCEPROP 1 LASTPIN (250 2800) $PN 2
J 0
(260 2780);
DISPLAY 0.787234 (260 2780);
PAINT ORANGE (260 2780);
DISPLAY INVISIBLE (260 2780);
FORCEPROP 1 LASTPIN (250 3000) $PN 1
J 0
(260 2980);
DISPLAY 0.787234 (260 2980);
PAINT ORANGE (260 2980);
DISPLAY INVISIBLE (260 2980);
FORCEADD P3V3_STBY..1
(725 2225);
FORCEPROP 3 LASTPIN (725 2175) SIG_NAME P3V3_STBY\g
J 0
(735 2185);
DISPLAY 0.659574 (735 2185);
PAINT MONO (735 2185);
DISPLAY INVISIBLE (735 2185);
FORCEPROP 1 LAST PATH I54
J 0
(770 2227);
DISPLAY 0.340426 (770 2227);
PAINT GREEN (770 2227);
DISPLAY INVISIBLE (770 2227);
FORCEPROP 1 LAST VOLTAGE 3.3V
J 0
(680 2182);
DISPLAY 0.340426 (680 2182);
PAINT GREEN (680 2182);
DISPLAY INVISIBLE (680 2182);
FORCEPROP 2 LAST CDS_LIB mstr_symbols
J 0
(725 2225);
PAINT MONO (725 2225);
DISPLAY INVISIBLE (725 2225);
FORCEPROP 1 LAST SIZE 1B
J 0
(770 2247);
DISPLAY 0.340426 (770 2247);
PAINT GREEN (770 2247);
DISPLAY INVISIBLE (770 2247);
FORCEPROP 1 LAST BODY_TYPE PLUMBING
J 0
(680 2182);
DISPLAY 0.340426 (680 2182);
PAINT GREEN (680 2182);
DISPLAY INVISIBLE (680 2182);
FORCEPROP 1 LAST HDL_POWER P3V3_STBY
J 0
(425 2100);
DISPLAY 0.872340 (425 2100);
PAINT ORANGE (425 2100);
DISPLAY INVISIBLE (425 2100);
FORCEADD GND..1
(475 2400);
FORCEPROP 3 LASTPIN (475 2450) SIG_NAME GND\g
J 0
(485 2460);
DISPLAY 0.659574 (485 2460);
PAINT MONO (485 2460);
DISPLAY INVISIBLE (485 2460);
FORCEPROP 1 LAST PATH I55
J 0
(550 2400);
DISPLAY 0.872340 (550 2400);
PAINT AQUA (550 2400);
DISPLAY INVISIBLE (550 2400);
FORCEPROP 1 LAST VOLTAGE 0.0V
J 0
(430 2357);
DISPLAY 0.340426 (430 2357);
PAINT GREEN (430 2357);
DISPLAY INVISIBLE (430 2357);
FORCEPROP 1 LAST BODY_TYPE PLUMBING
J 0
(430 2357);
DISPLAY 0.340426 (430 2357);
PAINT GREEN (430 2357);
DISPLAY INVISIBLE (430 2357);
FORCEPROP 1 LAST SIZE 1B
J 0
(550 2350);
DISPLAY 0.872340 (550 2350);
PAINT AQUA (550 2350);
DISPLAY INVISIBLE (550 2350);
FORCEPROP 1 LAST HDL_POWER GND
J 0
(475 2550);
DISPLAY 0.872340 (475 2550);
PAINT GREEN (475 2550);
DISPLAY INVISIBLE (475 2550);
FORCEPROP 2 LAST CDS_LIB mstr_symbols
J 0
(475 2400);
PAINT MONO (475 2400);
DISPLAY INVISIBLE (475 2400);
FORCEADD W_VCC_CIRCLE..1
(-2250 5625);
FORCEPROP 3 LASTPIN (-2250 5625) SIG_NAME P1V15_AUX_BMC\g
J 0
(-2240 5635);
DISPLAY 0.659574 (-2240 5635);
PAINT MONO (-2240 5635);
DISPLAY INVISIBLE (-2240 5635);
FORCEPROP 1 LAST HDL_POWER P1V15_AUX_BMC
J 1
(-2229 5700);
DISPLAY 0.872340 (-2229 5700);
PAINT ORANGE (-2229 5700);
FORCEPROP 1 LAST PATH I62
J 0
(-2250 5625);
DISPLAY 0.617021 (-2250 5625);
PAINT GREEN (-2250 5625);
DISPLAY INVISIBLE (-2250 5625);
FORCEPROP 2 LAST CDS_LIB w_power
J 0
(-2250 5625);
PAINT MONO (-2250 5625);
DISPLAY INVISIBLE (-2250 5625);
FORCEPROP 1 LAST CDS_LMAN_SYM_OUTLINE -100,100,100,-100
J 0
(-2250 5625);
DISPLAY 0.468085 (-2250 5625);
PAINT GREEN (-2250 5625);
DISPLAY INVISIBLE (-2250 5625);
FORCEPROP 1 LAST BODY_TYPE PLUMBING
J 0
(-2238 5619);
DISPLAY 0.340426 (-2238 5619);
PAINT GREEN (-2238 5619);
DISPLAY INVISIBLE (-2238 5619);
FORCEADD P3V3_STBY..1
(-175 4425);
FORCEPROP 3 LASTPIN (-175 4375) SIG_NAME P3V3_STBY\g
J 0
(-165 4385);
DISPLAY 0.659574 (-165 4385);
PAINT MONO (-165 4385);
DISPLAY INVISIBLE (-165 4385);
FORCEPROP 1 LAST PATH I65
J 0
(-130 4427);
DISPLAY 0.340426 (-130 4427);
PAINT GREEN (-130 4427);
DISPLAY INVISIBLE (-130 4427);
FORCEPROP 1 LAST VOLTAGE 3.3V
J 0
(-220 4382);
DISPLAY 0.340426 (-220 4382);
PAINT GREEN (-220 4382);
DISPLAY INVISIBLE (-220 4382);
FORCEPROP 2 LAST CDS_LIB mstr_symbols
J 0
(-175 4425);
PAINT MONO (-175 4425);
DISPLAY INVISIBLE (-175 4425);
FORCEPROP 1 LAST HDL_POWER P3V3_STBY
J 0
(-475 4300);
DISPLAY 0.872340 (-475 4300);
PAINT ORANGE (-475 4300);
DISPLAY INVISIBLE (-475 4300);
FORCEPROP 1 LAST BODY_TYPE PLUMBING
J 0
(-220 4382);
DISPLAY 0.340426 (-220 4382);
PAINT GREEN (-220 4382);
DISPLAY INVISIBLE (-220 4382);
FORCEPROP 1 LAST SIZE 1B
J 0
(-130 4447);
DISPLAY 0.340426 (-130 4447);
PAINT GREEN (-130 4447);
DISPLAY INVISIBLE (-130 4447);
FORCEADD W_VCC_CIRCLE..1
(-675 4475);
FORCEPROP 3 LASTPIN (-675 4475) SIG_NAME VCC_ADCAV3V3\g
J 0
(-665 4485);
DISPLAY 0.659574 (-665 4485);
PAINT MONO (-665 4485);
DISPLAY INVISIBLE (-665 4485);
FORCEPROP 1 LAST HDL_POWER VCC_ADCAV3V3
J 1
(-654 4550);
DISPLAY 0.872340 (-654 4550);
PAINT ORANGE (-654 4550);
FORCEPROP 1 LAST PATH I66
J 0
(-675 4475);
DISPLAY 0.617021 (-675 4475);
PAINT GREEN (-675 4475);
DISPLAY INVISIBLE (-675 4475);
FORCEPROP 1 LAST BODY_TYPE PLUMBING
J 0
(-663 4469);
DISPLAY 0.340426 (-663 4469);
PAINT GREEN (-663 4469);
DISPLAY INVISIBLE (-663 4469);
FORCEPROP 2 LAST CDS_LIB w_power
J 0
(-675 4475);
PAINT MONO (-675 4475);
DISPLAY INVISIBLE (-675 4475);
FORCEPROP 1 LAST CDS_LMAN_SYM_OUTLINE -100,100,100,-100
J 0
(-675 4475);
DISPLAY 0.468085 (-675 4475);
PAINT GREEN (-675 4475);
DISPLAY INVISIBLE (-675 4475);
FORCEADD GND..1
(-675 3600);
FORCEPROP 3 LASTPIN (-675 3650) SIG_NAME GND\g
J 0
(-665 3660);
DISPLAY 0.659574 (-665 3660);
PAINT MONO (-665 3660);
DISPLAY INVISIBLE (-665 3660);
FORCEPROP 1 LAST PATH I68
J 0
(-600 3600);
DISPLAY 0.872340 (-600 3600);
PAINT AQUA (-600 3600);
DISPLAY INVISIBLE (-600 3600);
FORCEPROP 1 LAST VOLTAGE 0.0V
J 0
(-720 3557);
DISPLAY 0.340426 (-720 3557);
PAINT GREEN (-720 3557);
DISPLAY INVISIBLE (-720 3557);
FORCEPROP 1 LAST BODY_TYPE PLUMBING
J 0
(-720 3557);
DISPLAY 0.340426 (-720 3557);
PAINT GREEN (-720 3557);
DISPLAY INVISIBLE (-720 3557);
FORCEPROP 2 LAST CDS_LIB mstr_symbols
J 0
(-675 3600);
PAINT MONO (-675 3600);
DISPLAY INVISIBLE (-675 3600);
FORCEPROP 1 LAST SIZE 1B
J 0
(-600 3550);
DISPLAY 0.872340 (-600 3550);
PAINT AQUA (-600 3550);
DISPLAY INVISIBLE (-600 3550);
FORCEPROP 1 LAST HDL_POWER GND
J 0
(-675 3750);
DISPLAY 0.872340 (-675 3750);
PAINT GREEN (-675 3750);
DISPLAY INVISIBLE (-675 3750);
FORCEADD W_VCC_CIRCLE..1
(-100 3350);
FORCEPROP 3 LASTPIN (-100 3350) SIG_NAME VCC_D_3V3\g
J 0
(-90 3360);
DISPLAY 0.659574 (-90 3360);
PAINT MONO (-90 3360);
DISPLAY INVISIBLE (-90 3360);
FORCEPROP 1 LAST HDL_POWER VCC_D_3V3
J 1
(-79 3425);
DISPLAY 0.872340 (-79 3425);
PAINT ORANGE (-79 3425);
FORCEPROP 1 LAST PATH I69
J 0
(-100 3350);
DISPLAY 0.617021 (-100 3350);
PAINT GREEN (-100 3350);
DISPLAY INVISIBLE (-100 3350);
FORCEPROP 1 LAST CDS_LMAN_SYM_OUTLINE -100,100,100,-100
J 0
(-100 3350);
DISPLAY 0.468085 (-100 3350);
PAINT GREEN (-100 3350);
DISPLAY INVISIBLE (-100 3350);
FORCEPROP 2 LAST CDS_LIB w_power
J 0
(-100 3350);
PAINT MONO (-100 3350);
DISPLAY INVISIBLE (-100 3350);
FORCEPROP 1 LAST BODY_TYPE PLUMBING
J 0
(-88 3344);
DISPLAY 0.340426 (-88 3344);
PAINT GREEN (-88 3344);
DISPLAY INVISIBLE (-88 3344);
FORCEADD GND..1
(5000 2550);
FORCEPROP 3 LASTPIN (5000 2600) SIG_NAME GND\g
J 0
(5010 2610);
DISPLAY 0.659574 (5010 2610);
PAINT MONO (5010 2610);
DISPLAY INVISIBLE (5010 2610);
FORCEPROP 2 LAST CDS_LIB mstr_symbols
J 0
(5000 2550);
PAINT MONO (5000 2550);
DISPLAY INVISIBLE (5000 2550);
FORCEPROP 1 LAST HDL_POWER GND
J 0
(5000 2700);
DISPLAY 0.872340 (5000 2700);
PAINT GREEN (5000 2700);
DISPLAY INVISIBLE (5000 2700);
FORCEPROP 1 LAST SIZE 1B
J 0
(5075 2500);
DISPLAY 0.872340 (5075 2500);
PAINT AQUA (5075 2500);
DISPLAY INVISIBLE (5075 2500);
FORCEPROP 1 LAST BODY_TYPE PLUMBING
J 0
(4955 2507);
DISPLAY 0.340426 (4955 2507);
PAINT GREEN (4955 2507);
DISPLAY INVISIBLE (4955 2507);
FORCEPROP 1 LAST VOLTAGE 0.0V
J 0
(4955 2507);
DISPLAY 0.340426 (4955 2507);
PAINT GREEN (4955 2507);
DISPLAY INVISIBLE (4955 2507);
FORCEPROP 1 LAST PATH I7
J 0
(5075 2550);
DISPLAY 0.872340 (5075 2550);
PAINT AQUA (5075 2550);
DISPLAY INVISIBLE (5075 2550);
FORCEADD W_VCC_CIRCLE..1
(-550 2300);
FORCEPROP 3 LASTPIN (-550 2300) SIG_NAME VCC_PA_3V3\g
J 0
(-540 2310);
DISPLAY 0.659574 (-540 2310);
PAINT MONO (-540 2310);
DISPLAY INVISIBLE (-540 2310);
FORCEPROP 1 LAST HDL_POWER VCC_PA_3V3
J 1
(-529 2375);
DISPLAY 0.872340 (-529 2375);
PAINT ORANGE (-529 2375);
FORCEPROP 1 LAST PATH I78
J 0
(-550 2300);
DISPLAY 0.617021 (-550 2300);
PAINT GREEN (-550 2300);
DISPLAY INVISIBLE (-550 2300);
FORCEPROP 2 LAST CDS_LIB w_power
J 0
(-550 2300);
PAINT MONO (-550 2300);
DISPLAY INVISIBLE (-550 2300);
FORCEPROP 1 LAST CDS_LMAN_SYM_OUTLINE -100,100,100,-100
J 0
(-550 2300);
DISPLAY 0.468085 (-550 2300);
PAINT GREEN (-550 2300);
DISPLAY INVISIBLE (-550 2300);
FORCEPROP 1 LAST BODY_TYPE PLUMBING
J 0
(-538 2294);
DISPLAY 0.340426 (-538 2294);
PAINT GREEN (-538 2294);
DISPLAY INVISIBLE (-538 2294);
FORCEADD CAP..1
(-550 1850);
FORCEPROP 1 LAST PACK_TYPE 0603
J 0
(-500 1725);
DISPLAY 0.638298 (-500 1725);
PAINT SKYBLUE (-500 1725);
FORCEPROP 1 LASTPIN (-550 1950) $PN 1
J 0
(-540 1930);
DISPLAY 0.787234 (-540 1930);
PAINT ORANGE (-540 1930);
FORCEPROP 1 LAST LOCATION C25W59
J 0
(-500 1975);
DISPLAY 0.638298 (-500 1975);
PAINT SKYBLUE (-500 1975);
FORCEPROP 0 LAST POP NOPOP
J 0
(-500 1625);
DISPLAY 0.808511 (-500 1625);
PAINT RED (-500 1625);
FORCEPROP 1 LAST VALUE 4.7UF
J 0
(-500 1925);
DISPLAY 0.638298 (-500 1925);
PAINT SKYBLUE (-500 1925);
FORCEPROP 1 LAST VOLTAGE 6.3V
J 0
(-500 1875);
DISPLAY 0.638298 (-500 1875);
PAINT SKYBLUE (-500 1875);
FORCEPROP 1 LAST TOLERANCE 10%
J 0
(-500 1825);
DISPLAY 0.638298 (-500 1825);
PAINT SKYBLUE (-500 1825);
FORCEPROP 1 LAST MATERIAL X6S
J 0
(-500 1775);
DISPLAY 0.638298 (-500 1775);
PAINT SKYBLUE (-500 1775);
FORCEPROP 1 LASTPIN (-550 1750) $PN 2
J 0
(-540 1730);
DISPLAY 0.787234 (-540 1730);
PAINT ORANGE (-540 1730);
FORCEPROP 1 LAST PART_NUMBER E15431-003
J 0
(-500 1675);
DISPLAY 0.638298 (-500 1675);
PAINT BLUE (-500 1675);
FORCEPROP 2 LAST SEC_TYPE 0603
J 0
(-500 2050);
DISPLAY 1.021277 (-500 2050);
PAINT ORANGE (-500 2050);
DISPLAY INVISIBLE (-500 2050);
FORCEPROP 0 LAST SEC 1
J 0
(-500 2025);
PAINT MONO (-500 2025);
DISPLAY INVISIBLE (-500 2025);
FORCEPROP 1 LAST PATH I79
J 0
(-500 2000);
DISPLAY 0.978723 (-500 2000);
PAINT WHITE (-500 2000);
DISPLAY INVISIBLE (-500 2000);
FORCEPROP 0 LAST CDS_LOCATION C25W59
J 0
(-500 2025);
PAINT MONO (-500 2025);
DISPLAY INVISIBLE (-500 2025);
FORCEPROP 2 LAST CDS_LIB mstr_discrete
J 0
(-550 1850);
PAINT MONO (-550 1850);
DISPLAY INVISIBLE (-550 1850);
FORCEADD GND..1
(-550 1425);
FORCEPROP 3 LASTPIN (-550 1475) SIG_NAME GND\g
J 0
(-540 1485);
DISPLAY 0.659574 (-540 1485);
PAINT MONO (-540 1485);
DISPLAY INVISIBLE (-540 1485);
FORCEPROP 1 LAST SIZE 1B
J 0
(-475 1375);
DISPLAY 0.872340 (-475 1375);
PAINT AQUA (-475 1375);
DISPLAY INVISIBLE (-475 1375);
FORCEPROP 1 LAST HDL_POWER GND
J 0
(-550 1575);
DISPLAY 0.872340 (-550 1575);
PAINT GREEN (-550 1575);
DISPLAY INVISIBLE (-550 1575);
FORCEPROP 2 LAST CDS_LIB mstr_symbols
J 0
(-550 1425);
PAINT MONO (-550 1425);
DISPLAY INVISIBLE (-550 1425);
FORCEPROP 1 LAST BODY_TYPE PLUMBING
J 0
(-595 1382);
DISPLAY 0.340426 (-595 1382);
PAINT GREEN (-595 1382);
DISPLAY INVISIBLE (-595 1382);
FORCEPROP 1 LAST VOLTAGE 0.0V
J 0
(-595 1382);
DISPLAY 0.340426 (-595 1382);
PAINT GREEN (-595 1382);
DISPLAY INVISIBLE (-595 1382);
FORCEPROP 1 LAST PATH I80
J 0
(-475 1425);
DISPLAY 0.872340 (-475 1425);
PAINT AQUA (-475 1425);
DISPLAY INVISIBLE (-475 1425);
FORCEADD P3V3_STBY..1
(-2350 4550);
FORCEPROP 3 LASTPIN (-2350 4500) SIG_NAME P3V3_STBY\g
J 0
(-2340 4510);
DISPLAY 0.659574 (-2340 4510);
PAINT MONO (-2340 4510);
DISPLAY INVISIBLE (-2340 4510);
FORCEPROP 1 LAST PATH I84
J 0
(-2305 4552);
DISPLAY 0.340426 (-2305 4552);
PAINT GREEN (-2305 4552);
DISPLAY INVISIBLE (-2305 4552);
FORCEPROP 1 LAST HDL_POWER P3V3_STBY
J 0
(-2650 4425);
DISPLAY 0.872340 (-2650 4425);
PAINT ORANGE (-2650 4425);
DISPLAY INVISIBLE (-2650 4425);
FORCEPROP 1 LAST BODY_TYPE PLUMBING
J 0
(-2395 4507);
DISPLAY 0.340426 (-2395 4507);
PAINT GREEN (-2395 4507);
DISPLAY INVISIBLE (-2395 4507);
FORCEPROP 1 LAST SIZE 1B
J 0
(-2305 4572);
DISPLAY 0.340426 (-2305 4572);
PAINT GREEN (-2305 4572);
DISPLAY INVISIBLE (-2305 4572);
FORCEPROP 2 LAST CDS_LIB mstr_symbols
J 0
(-2350 4550);
PAINT MONO (-2350 4550);
DISPLAY INVISIBLE (-2350 4550);
FORCEPROP 1 LAST VOLTAGE 3.3V
J 0
(-2395 4507);
DISPLAY 0.340426 (-2395 4507);
PAINT GREEN (-2395 4507);
DISPLAY INVISIBLE (-2395 4507);
FORCEADD HCB1608KF-800T30-GP..1
R 1
(-2075 4400);
FORCEPROP 2 LAST PACK_SIZE DCR=4MOHM
J 0
(-2175 4175);
DISPLAY 0.638298 (-2175 4175);
PAINT GREEN (-2175 4175);
FORCEPROP 2 LAST RATED 3A
J 0
(-2175 4225);
DISPLAY 0.638298 (-2175 4225);
PAINT GREEN (-2175 4225);
FORCEPROP 2 LAST ATTRIBUTE 80OHM@100MHZ
J 0
(-2175 4275);
DISPLAY 0.638298 (-2175 4275);
PAINT GREEN (-2175 4275);
FORCEPROP 1 LAST VALUE HCB1608KF-800T30-GP
J 0
(-2175 4325);
DISPLAY 0.617021 (-2175 4325);
PAINT GREEN (-2175 4325);
FORCEPROP 1 LAST LOCATION FB2T3
J 0
(-2150 4450);
DISPLAY 0.617021 (-2150 4450);
PAINT GREEN (-2150 4450);
FORCEPROP 0 LASTPIN (-1925 4400) $PN 2
J 0
(-1915 4410);
DISPLAY 0.808511 (-1915 4410);
PAINT MONO (-1915 4410);
FORCEPROP 0 LASTPIN (-2225 4400) $PN 1
J 2
(-2235 4410);
DISPLAY 0.808511 (-2235 4410);
PAINT MONO (-2235 4410);
FORCEPROP 1 LAST PATH I85
R 1
J 0
(-2075 4400);
DISPLAY 0.617021 (-2075 4400);
PAINT GREEN (-2075 4400);
DISPLAY INVISIBLE (-2075 4400);
FORCEPROP 0 LAST CDS_SEC 1
R 1
J 0
(-2150 4500);
PAINT MONO (-2150 4500);
DISPLAY INVISIBLE (-2150 4500);
FORCEPROP 0 LAST $SEC 1
R 1
J 0
(-2150 4500);
PAINT MONO (-2150 4500);
DISPLAY INVISIBLE (-2150 4500);
FORCEPROP 0 LAST CDS_LOCATION FB2T3
R 1
J 0
(-2150 4500);
PAINT MONO (-2150 4500);
DISPLAY INVISIBLE (-2150 4500);
FORCEPROP 1 LAST PACK_TYPE DISCRET-G9
R 1
J 0
(-2075 4400);
DISPLAY 0.617021 (-2075 4400);
PAINT GREEN (-2075 4400);
DISPLAY INVISIBLE (-2075 4400);
FORCEPROP 1 LAST PART_NUMBER 68.00230.231
R 1
J 0
(-2075 4400);
DISPLAY 0.617021 (-2075 4400);
PAINT GREEN (-2075 4400);
DISPLAY INVISIBLE (-2075 4400);
FORCEPROP 2 LAST CDS_LIB w_hdl
R 1
J 0
(-2075 4400);
PAINT MONO (-2075 4400);
DISPLAY INVISIBLE (-2075 4400);
FORCEPROP 1 LAST CDS_LMAN_SYM_OUTLINE -50,100,50,-100
R 1
J 0
(-2075 4400);
DISPLAY 0.468085 (-2075 4400);
PAINT GREEN (-2075 4400);
DISPLAY INVISIBLE (-2075 4400);
FORCEADD HCB1608KF-800T30-GP..1
R 1
(-2050 3200);
FORCEPROP 2 LAST RATED 3A
J 0
(-2150 3025);
DISPLAY 0.638298 (-2150 3025);
PAINT GREEN (-2150 3025);
FORCEPROP 2 LAST ATTRIBUTE 80OHM@100MHZ
J 0
(-2150 3075);
DISPLAY 0.638298 (-2150 3075);
PAINT GREEN (-2150 3075);
FORCEPROP 1 LAST LOCATION FB2T4
J 0
(-2125 3250);
DISPLAY 0.617021 (-2125 3250);
PAINT GREEN (-2125 3250);
FORCEPROP 1 LAST VALUE HCB1608KF-800T30-GP
J 0
(-2150 3125);
DISPLAY 0.617021 (-2150 3125);
PAINT GREEN (-2150 3125);
FORCEPROP 0 LASTPIN (-1900 3200) $PN 2
J 0
(-1890 3210);
DISPLAY 0.808511 (-1890 3210);
PAINT MONO (-1890 3210);
FORCEPROP 0 LASTPIN (-2200 3200) $PN 1
J 2
(-2210 3210);
DISPLAY 0.808511 (-2210 3210);
PAINT MONO (-2210 3210);
FORCEPROP 2 LAST PACK_SIZE DCR=4MOHM
J 0
(-2150 2975);
DISPLAY 0.638298 (-2150 2975);
PAINT GREEN (-2150 2975);
FORCEPROP 1 LAST PATH I86
R 1
J 0
(-2050 3200);
DISPLAY 0.617021 (-2050 3200);
PAINT GREEN (-2050 3200);
DISPLAY INVISIBLE (-2050 3200);
FORCEPROP 0 LAST CDS_SEC 1
R 1
J 0
(-2125 3300);
PAINT MONO (-2125 3300);
DISPLAY INVISIBLE (-2125 3300);
FORCEPROP 0 LAST $SEC 1
R 1
J 0
(-2125 3300);
PAINT MONO (-2125 3300);
DISPLAY INVISIBLE (-2125 3300);
FORCEPROP 0 LAST CDS_LOCATION FB2T4
R 1
J 0
(-2125 3300);
PAINT MONO (-2125 3300);
DISPLAY INVISIBLE (-2125 3300);
FORCEPROP 2 LAST CDS_LIB w_hdl
J 0
(-2050 3200);
PAINT MONO (-2050 3200);
DISPLAY INVISIBLE (-2050 3200);
FORCEPROP 1 LAST CDS_LMAN_SYM_OUTLINE -50,100,50,-100
R 1
J 0
(-2050 3200);
DISPLAY 0.468085 (-2050 3200);
PAINT GREEN (-2050 3200);
DISPLAY INVISIBLE (-2050 3200);
FORCEPROP 1 LAST PACK_TYPE DISCRET-G9
R 1
J 0
(-2050 3200);
DISPLAY 0.617021 (-2050 3200);
PAINT GREEN (-2050 3200);
DISPLAY INVISIBLE (-2050 3200);
FORCEPROP 1 LAST PART_NUMBER 68.00230.231
R 1
J 0
(-2050 3200);
DISPLAY 0.617021 (-2050 3200);
PAINT GREEN (-2050 3200);
DISPLAY INVISIBLE (-2050 3200);
FORCEADD P3V3_STBY..1
(-2325 3350);
FORCEPROP 3 LASTPIN (-2325 3300) SIG_NAME P3V3_STBY\g
J 0
(-2315 3310);
DISPLAY 0.659574 (-2315 3310);
PAINT MONO (-2315 3310);
DISPLAY INVISIBLE (-2315 3310);
FORCEPROP 1 LAST PATH I87
J 0
(-2280 3352);
DISPLAY 0.340426 (-2280 3352);
PAINT GREEN (-2280 3352);
DISPLAY INVISIBLE (-2280 3352);
FORCEPROP 1 LAST SIZE 1B
J 0
(-2280 3372);
DISPLAY 0.340426 (-2280 3372);
PAINT GREEN (-2280 3372);
DISPLAY INVISIBLE (-2280 3372);
FORCEPROP 1 LAST BODY_TYPE PLUMBING
J 0
(-2370 3307);
DISPLAY 0.340426 (-2370 3307);
PAINT GREEN (-2370 3307);
DISPLAY INVISIBLE (-2370 3307);
FORCEPROP 1 LAST HDL_POWER P3V3_STBY
J 0
(-2625 3225);
DISPLAY 0.872340 (-2625 3225);
PAINT ORANGE (-2625 3225);
DISPLAY INVISIBLE (-2625 3225);
FORCEPROP 2 LAST CDS_LIB mstr_symbols
J 0
(-2325 3350);
PAINT MONO (-2325 3350);
DISPLAY INVISIBLE (-2325 3350);
FORCEPROP 1 LAST VOLTAGE 3.3V
J 0
(-2370 3307);
DISPLAY 0.340426 (-2370 3307);
PAINT GREEN (-2370 3307);
DISPLAY INVISIBLE (-2370 3307);
FORCEADD HCB1608KF-800T30-GP..1
R 1
(-2025 2150);
FORCEPROP 0 LASTPIN (-1875 2150) $PN 2
J 0
(-1865 2160);
DISPLAY 0.808511 (-1865 2160);
PAINT MONO (-1865 2160);
FORCEPROP 1 LAST LOCATION FB2T5
J 0
(-2100 2200);
DISPLAY 0.617021 (-2100 2200);
PAINT GREEN (-2100 2200);
FORCEPROP 2 LAST RATED 3A
J 0
(-2125 1975);
DISPLAY 0.638298 (-2125 1975);
PAINT GREEN (-2125 1975);
FORCEPROP 2 LAST PACK_SIZE DCR=4MOHM
J 0
(-2125 1925);
DISPLAY 0.638298 (-2125 1925);
PAINT GREEN (-2125 1925);
FORCEPROP 2 LAST ATTRIBUTE 80OHM@100MHZ
J 0
(-2125 2025);
DISPLAY 0.638298 (-2125 2025);
PAINT GREEN (-2125 2025);
FORCEPROP 1 LAST VALUE HCB1608KF-800T30-GP
J 0
(-2125 2075);
DISPLAY 0.617021 (-2125 2075);
PAINT GREEN (-2125 2075);
FORCEPROP 0 LASTPIN (-2175 2150) $PN 1
J 2
(-2185 2160);
DISPLAY 0.808511 (-2185 2160);
PAINT MONO (-2185 2160);
FORCEPROP 1 LAST PATH I88
R 1
J 0
(-2025 2150);
DISPLAY 0.617021 (-2025 2150);
PAINT GREEN (-2025 2150);
DISPLAY INVISIBLE (-2025 2150);
FORCEPROP 0 LAST CDS_SEC 1
R 1
J 0
(-2100 2250);
PAINT MONO (-2100 2250);
DISPLAY INVISIBLE (-2100 2250);
FORCEPROP 0 LAST $SEC 1
R 1
J 0
(-2100 2250);
PAINT MONO (-2100 2250);
DISPLAY INVISIBLE (-2100 2250);
FORCEPROP 0 LAST CDS_LOCATION FB2T5
R 1
J 0
(-2100 2250);
PAINT MONO (-2100 2250);
DISPLAY INVISIBLE (-2100 2250);
FORCEPROP 1 LAST PART_NUMBER 68.00230.231
R 1
J 0
(-2025 2150);
DISPLAY 0.617021 (-2025 2150);
PAINT GREEN (-2025 2150);
DISPLAY INVISIBLE (-2025 2150);
FORCEPROP 1 LAST PACK_TYPE DISCRET-G9
R 1
J 0
(-2025 2150);
DISPLAY 0.617021 (-2025 2150);
PAINT GREEN (-2025 2150);
DISPLAY INVISIBLE (-2025 2150);
FORCEPROP 2 LAST CDS_LIB w_hdl
J 0
(-2025 2150);
PAINT MONO (-2025 2150);
DISPLAY INVISIBLE (-2025 2150);
FORCEPROP 1 LAST CDS_LMAN_SYM_OUTLINE -50,100,50,-100
R 1
J 0
(-2025 2150);
DISPLAY 0.468085 (-2025 2150);
PAINT GREEN (-2025 2150);
DISPLAY INVISIBLE (-2025 2150);
FORCEADD P3V3_STBY..1
(-2325 2300);
FORCEPROP 3 LASTPIN (-2325 2250) SIG_NAME P3V3_STBY\g
J 0
(-2315 2260);
DISPLAY 0.659574 (-2315 2260);
PAINT MONO (-2315 2260);
DISPLAY INVISIBLE (-2315 2260);
FORCEPROP 1 LAST PATH I89
J 0
(-2280 2302);
DISPLAY 0.340426 (-2280 2302);
PAINT GREEN (-2280 2302);
DISPLAY INVISIBLE (-2280 2302);
FORCEPROP 1 LAST HDL_POWER P3V3_STBY
J 0
(-2625 2175);
DISPLAY 0.872340 (-2625 2175);
PAINT ORANGE (-2625 2175);
DISPLAY INVISIBLE (-2625 2175);
FORCEPROP 1 LAST BODY_TYPE PLUMBING
J 0
(-2370 2257);
DISPLAY 0.340426 (-2370 2257);
PAINT GREEN (-2370 2257);
DISPLAY INVISIBLE (-2370 2257);
FORCEPROP 1 LAST SIZE 1B
J 0
(-2280 2322);
DISPLAY 0.340426 (-2280 2322);
PAINT GREEN (-2280 2322);
DISPLAY INVISIBLE (-2280 2322);
FORCEPROP 2 LAST CDS_LIB mstr_symbols
J 0
(-2325 2300);
PAINT MONO (-2325 2300);
DISPLAY INVISIBLE (-2325 2300);
FORCEPROP 1 LAST VOLTAGE 3.3V
J 0
(-2370 2257);
DISPLAY 0.340426 (-2370 2257);
PAINT GREEN (-2370 2257);
DISPLAY INVISIBLE (-2370 2257);
FORCEADD RES..1
(125 4275);
FORCEPROP 1 LAST PART_NUMBER G22178-002
J 0
(-225 4225);
DISPLAY 0.617021 (-225 4225);
PAINT BLUE (-225 4225);
FORCEPROP 1 LAST LOCATION R25W93
J 0
(50 4325);
DISPLAY 0.617021 (50 4325);
PAINT AQUA (50 4325);
FORCEPROP 1 LAST PACK_TYPE 0603
J 0
(200 4225);
DISPLAY 0.617021 (200 4225);
PAINT SKYBLUE (200 4225);
FORCEPROP 1 LAST VALUE 0
J 2
(75 4225);
DISPLAY 0.617021 (75 4225);
PAINT SKYBLUE (75 4225);
FORCEPROP 1 LAST TOLERANCE 5.0%
J 0
(125 4175);
DISPLAY 0.617021 (125 4175);
PAINT SKYBLUE (125 4175);
FORCEPROP 1 LAST WATTAGE 1/10W
J 0
(100 4125);
DISPLAY 0.617021 (100 4125);
PAINT SKYBLUE (100 4125);
FORCEPROP 1 LAST MATERIAL CHIP
J 0
(125 4075);
DISPLAY 0.617021 (125 4075);
PAINT SKYBLUE (125 4075);
FORCEPROP 1 LASTPIN (225 4275) $PN 2
J 0
(187 4287);
DISPLAY 0.787234 (187 4287);
PAINT ORANGE (187 4287);
DISPLAY INVISIBLE (187 4287);
FORCEPROP 1 LASTPIN (25 4275) $PN 1
J 0
(37 4287);
DISPLAY 0.787234 (37 4287);
PAINT ORANGE (37 4287);
DISPLAY INVISIBLE (37 4287);
FORCEPROP 2 LAST CDS_LIB mstr_discrete
J 0
(125 4275);
PAINT MONO (125 4275);
DISPLAY INVISIBLE (125 4275);
FORCEPROP 1 LAST PATH I90
J 0
(75 4425);
DISPLAY 0.978723 (75 4425);
PAINT WHITE (75 4425);
DISPLAY INVISIBLE (75 4425);
FORCEPROP 0 LAST BOM_COST NT_GBE_BASE
J 0
(225 4500);
DISPLAY 1.021277 (225 4500);
PAINT ORANGE (225 4500);
DISPLAY INVISIBLE (225 4500);
FORCEPROP 0 LAST ROOM NIC_SPRV
J 0
(225 4400);
DISPLAY 1.021277 (225 4400);
PAINT ORANGE (225 4400);
DISPLAY INVISIBLE (225 4400);
FORCEADD RES..1
(4100 5500);
FORCEPROP 1 LAST PART_NUMBER G22178-002
J 0
(3750 5450);
DISPLAY 0.617021 (3750 5450);
PAINT BLUE (3750 5450);
FORCEPROP 1 LAST VALUE 0
J 2
(4050 5450);
DISPLAY 0.617021 (4050 5450);
PAINT SKYBLUE (4050 5450);
FORCEPROP 1 LAST LOCATION R25W120
J 0
(4025 5550);
DISPLAY 0.617021 (4025 5550);
PAINT AQUA (4025 5550);
FORCEPROP 1 LAST PACK_TYPE 0603
J 0
(4175 5450);
DISPLAY 0.617021 (4175 5450);
PAINT SKYBLUE (4175 5450);
FORCEPROP 1 LAST TOLERANCE 5.0%
J 0
(4100 5400);
DISPLAY 0.617021 (4100 5400);
PAINT SKYBLUE (4100 5400);
FORCEPROP 1 LAST WATTAGE 1/10W
J 0
(4075 5350);
DISPLAY 0.617021 (4075 5350);
PAINT SKYBLUE (4075 5350);
FORCEPROP 1 LAST MATERIAL CHIP
J 0
(4100 5300);
DISPLAY 0.617021 (4100 5300);
PAINT SKYBLUE (4100 5300);
FORCEPROP 1 LASTPIN (4200 5500) $PN 2
J 0
(4162 5512);
DISPLAY 0.787234 (4162 5512);
PAINT ORANGE (4162 5512);
DISPLAY INVISIBLE (4162 5512);
FORCEPROP 1 LASTPIN (4000 5500) $PN 1
J 0
(4012 5512);
DISPLAY 0.787234 (4012 5512);
PAINT ORANGE (4012 5512);
DISPLAY INVISIBLE (4012 5512);
FORCEPROP 0 LAST BOM_COST NT_GBE_BASE
J 0
(4200 5725);
DISPLAY 1.021277 (4200 5725);
PAINT ORANGE (4200 5725);
DISPLAY INVISIBLE (4200 5725);
FORCEPROP 0 LAST ROOM NIC_SPRV
J 0
(4200 5625);
DISPLAY 1.021277 (4200 5625);
PAINT ORANGE (4200 5625);
DISPLAY INVISIBLE (4200 5625);
FORCEPROP 1 LAST PATH I91
J 0
(4050 5650);
DISPLAY 0.978723 (4050 5650);
PAINT WHITE (4050 5650);
DISPLAY INVISIBLE (4050 5650);
FORCEPROP 2 LAST CDS_LIB mstr_discrete
J 0
(4100 5500);
PAINT MONO (4100 5500);
DISPLAY INVISIBLE (4100 5500);
FORCEADD CAP..1
(4500 2900);
FORCEPROP 1 LAST VALUE 1.0UF
J 0
(4550 2950);
DISPLAY 0.617021 (4550 2950);
PAINT SKYBLUE (4550 2950);
FORCEPROP 1 LAST LOCATION C25W53
J 0
(4550 3000);
DISPLAY 0.617021 (4550 3000);
PAINT AQUA (4550 3000);
FORCEPROP 1 LAST PACK_TYPE 0402
J 0
(4550 2700);
DISPLAY 0.617021 (4550 2700);
PAINT SKYBLUE (4550 2700);
FORCEPROP 1 LAST PART_NUMBER D97712-011
J 0
(4550 2750);
DISPLAY 0.617021 (4550 2750);
PAINT BLUE (4550 2750);
FORCEPROP 1 LASTPIN (4500 3000) $PN 1
J 0
(4510 2980);
DISPLAY 0.787234 (4510 2980);
PAINT ORANGE (4510 2980);
FORCEPROP 1 LAST MATERIAL X6S
J 0
(4550 2800);
DISPLAY 0.617021 (4550 2800);
PAINT SKYBLUE (4550 2800);
FORCEPROP 1 LAST VOLTAGE 16V
J 0
(4550 2900);
DISPLAY 0.617021 (4550 2900);
PAINT SKYBLUE (4550 2900);
FORCEPROP 1 LAST TOLERANCE 10%
J 0
(4550 2850);
DISPLAY 0.617021 (4550 2850);
PAINT SKYBLUE (4550 2850);
FORCEPROP 1 LASTPIN (4500 2800) $PN 2
J 0
(4510 2780);
DISPLAY 0.787234 (4510 2780);
PAINT ORANGE (4510 2780);
FORCEPROP 0 LAST ROOM PROC_SIDEBAND
J 0
(4550 3100);
DISPLAY 1.021277 (4550 3100);
PAINT ORANGE (4550 3100);
DISPLAY INVISIBLE (4550 3100);
FORCEPROP 0 LAST BOM_COST PROC
J 0
(4550 3100);
DISPLAY 1.021277 (4550 3100);
PAINT ORANGE (4550 3100);
DISPLAY INVISIBLE (4550 3100);
FORCEPROP 1 LAST PATH I92
J 0
(4550 3050);
DISPLAY 0.978723 (4550 3050);
PAINT WHITE (4550 3050);
DISPLAY INVISIBLE (4550 3050);
FORCEPROP 2 LAST SEC 1
J 0
(4550 3100);
DISPLAY 0.680851 (4550 3100);
PAINT MONO (4550 3100);
DISPLAY INVISIBLE (4550 3100);
FORCEPROP 2 LAST SEC_TYPE 0402
J 0
(4550 3100);
DISPLAY 1.021277 (4550 3100);
PAINT ORANGE (4550 3100);
DISPLAY INVISIBLE (4550 3100);
FORCEPROP 2 LAST CDS_LIB mstr_discrete
J 0
(4500 2900);
PAINT MONO (4500 2900);
DISPLAY INVISIBLE (4500 2900);
FORCEADD CAP..1
(-850 1850);
FORCEPROP 1 LAST TOLERANCE 10%
J 0
(-800 1800);
DISPLAY 0.617021 (-800 1800);
PAINT SKYBLUE (-800 1800);
FORCEPROP 1 LAST MATERIAL X6S
J 0
(-800 1750);
DISPLAY 0.617021 (-800 1750);
PAINT SKYBLUE (-800 1750);
FORCEPROP 1 LAST PACK_TYPE 0402
J 0
(-800 1650);
DISPLAY 0.617021 (-800 1650);
PAINT SKYBLUE (-800 1650);
FORCEPROP 1 LAST VOLTAGE 16V
J 0
(-800 1850);
DISPLAY 0.617021 (-800 1850);
PAINT SKYBLUE (-800 1850);
FORCEPROP 1 LAST VALUE 1.0UF
J 0
(-800 1900);
DISPLAY 0.617021 (-800 1900);
PAINT SKYBLUE (-800 1900);
FORCEPROP 1 LAST LOCATION C25W56
J 0
(-800 1950);
DISPLAY 0.617021 (-800 1950);
PAINT AQUA (-800 1950);
FORCEPROP 1 LAST PART_NUMBER D97712-011
J 0
(-800 1700);
DISPLAY 0.617021 (-800 1700);
PAINT BLUE (-800 1700);
FORCEPROP 1 LASTPIN (-850 1950) $PN 1
J 0
(-840 1930);
DISPLAY 0.787234 (-840 1930);
PAINT ORANGE (-840 1930);
DISPLAY INVISIBLE (-840 1930);
FORCEPROP 1 LASTPIN (-850 1750) $PN 2
J 0
(-840 1730);
DISPLAY 0.787234 (-840 1730);
PAINT ORANGE (-840 1730);
DISPLAY INVISIBLE (-840 1730);
FORCEPROP 2 LAST CDS_LIB mstr_discrete
J 0
(-850 1850);
PAINT MONO (-850 1850);
DISPLAY INVISIBLE (-850 1850);
FORCEPROP 1 LAST PATH I93
J 0
(-800 2000);
DISPLAY 0.978723 (-800 2000);
PAINT WHITE (-800 2000);
DISPLAY INVISIBLE (-800 2000);
FORCEPROP 0 LAST ROOM PROC_SIDEBAND
J 0
(-800 2050);
DISPLAY 1.021277 (-800 2050);
PAINT ORANGE (-800 2050);
DISPLAY INVISIBLE (-800 2050);
FORCEPROP 0 LAST BOM_COST PROC
J 0
(-800 2050);
DISPLAY 1.021277 (-800 2050);
PAINT ORANGE (-800 2050);
DISPLAY INVISIBLE (-800 2050);
FORCEADD CAP..1
(4750 2900);
FORCEPROP 1 LAST PACK_TYPE 0402
J 0
(4800 2700);
DISPLAY 0.617021 (4800 2700);
PAINT SKYBLUE (4800 2700);
FORCEPROP 1 LAST PART_NUMBER D97712-011
J 0
(4800 2750);
DISPLAY 0.617021 (4800 2750);
PAINT BLUE (4800 2750);
FORCEPROP 1 LAST MATERIAL X6S
J 0
(4800 2800);
DISPLAY 0.617021 (4800 2800);
PAINT SKYBLUE (4800 2800);
FORCEPROP 1 LAST TOLERANCE 10%
J 0
(4800 2850);
DISPLAY 0.617021 (4800 2850);
PAINT SKYBLUE (4800 2850);
FORCEPROP 1 LAST VOLTAGE 16V
J 0
(4800 2900);
DISPLAY 0.617021 (4800 2900);
PAINT SKYBLUE (4800 2900);
FORCEPROP 1 LAST VALUE 1.0UF
J 0
(4800 2950);
DISPLAY 0.617021 (4800 2950);
PAINT SKYBLUE (4800 2950);
FORCEPROP 1 LAST LOCATION C25W54
J 0
(4800 3000);
DISPLAY 0.617021 (4800 3000);
PAINT AQUA (4800 3000);
FORCEPROP 0 LAST BOM_COST PROC
J 0
(4800 3100);
DISPLAY 1.021277 (4800 3100);
PAINT ORANGE (4800 3100);
DISPLAY INVISIBLE (4800 3100);
FORCEPROP 0 LAST ROOM PROC_SIDEBAND
J 0
(4800 3100);
DISPLAY 1.021277 (4800 3100);
PAINT ORANGE (4800 3100);
DISPLAY INVISIBLE (4800 3100);
FORCEPROP 1 LAST PATH I95
J 0
(4800 3050);
DISPLAY 0.978723 (4800 3050);
PAINT WHITE (4800 3050);
DISPLAY INVISIBLE (4800 3050);
FORCEPROP 2 LAST CDS_LIB mstr_discrete
J 0
(4750 2900);
PAINT MONO (4750 2900);
DISPLAY INVISIBLE (4750 2900);
FORCEPROP 1 LASTPIN (4750 2800) $PN 2
J 0
(4760 2780);
DISPLAY 0.787234 (4760 2780);
PAINT ORANGE (4760 2780);
DISPLAY INVISIBLE (4760 2780);
FORCEPROP 1 LASTPIN (4750 3000) $PN 1
J 0
(4760 2980);
DISPLAY 0.787234 (4760 2980);
PAINT ORANGE (4760 2980);
DISPLAY INVISIBLE (4760 2980);
FORCEADD CAP..1
(-1450 2900);
FORCEPROP 1 LAST LOCATION C25W40
J 0
(-1400 3000);
DISPLAY 0.617021 (-1400 3000);
PAINT AQUA (-1400 3000);
FORCEPROP 1 LAST VALUE 1.0UF
J 0
(-1400 2950);
DISPLAY 0.617021 (-1400 2950);
PAINT SKYBLUE (-1400 2950);
FORCEPROP 1 LAST VOLTAGE 16V
J 0
(-1400 2900);
DISPLAY 0.617021 (-1400 2900);
PAINT SKYBLUE (-1400 2900);
FORCEPROP 1 LAST PART_NUMBER D97712-011
J 0
(-1400 2750);
DISPLAY 0.617021 (-1400 2750);
PAINT BLUE (-1400 2750);
FORCEPROP 1 LAST TOLERANCE 10%
J 0
(-1400 2850);
DISPLAY 0.617021 (-1400 2850);
PAINT SKYBLUE (-1400 2850);
FORCEPROP 1 LAST MATERIAL X6S
J 0
(-1400 2800);
DISPLAY 0.617021 (-1400 2800);
PAINT SKYBLUE (-1400 2800);
FORCEPROP 1 LAST PACK_TYPE 0402
J 0
(-1400 2700);
DISPLAY 0.617021 (-1400 2700);
PAINT SKYBLUE (-1400 2700);
FORCEPROP 0 LAST BOM_COST PROC
J 0
(-1400 3100);
DISPLAY 1.021277 (-1400 3100);
PAINT ORANGE (-1400 3100);
DISPLAY INVISIBLE (-1400 3100);
FORCEPROP 0 LAST ROOM PROC_SIDEBAND
J 0
(-1400 3100);
DISPLAY 1.021277 (-1400 3100);
PAINT ORANGE (-1400 3100);
DISPLAY INVISIBLE (-1400 3100);
FORCEPROP 1 LAST PATH I96
J 0
(-1400 3050);
DISPLAY 0.978723 (-1400 3050);
PAINT WHITE (-1400 3050);
DISPLAY INVISIBLE (-1400 3050);
FORCEPROP 2 LAST CDS_LIB mstr_discrete
J 0
(-1450 2900);
PAINT MONO (-1450 2900);
DISPLAY INVISIBLE (-1450 2900);
FORCEPROP 1 LASTPIN (-1450 2800) $PN 2
J 0
(-1440 2780);
DISPLAY 0.787234 (-1440 2780);
PAINT ORANGE (-1440 2780);
DISPLAY INVISIBLE (-1440 2780);
FORCEPROP 1 LASTPIN (-1450 3000) $PN 1
J 0
(-1440 2980);
DISPLAY 0.787234 (-1440 2980);
PAINT ORANGE (-1440 2980);
DISPLAY INVISIBLE (-1440 2980);
FORCEADD CAP..1
(-1150 2900);
FORCEPROP 1 LAST LOCATION C25W41
J 0
(-1100 3000);
DISPLAY 0.617021 (-1100 3000);
PAINT AQUA (-1100 3000);
FORCEPROP 1 LAST PART_NUMBER D97712-011
J 0
(-1100 2750);
DISPLAY 0.617021 (-1100 2750);
PAINT BLUE (-1100 2750);
FORCEPROP 1 LAST PACK_TYPE 0402
J 0
(-1100 2700);
DISPLAY 0.617021 (-1100 2700);
PAINT SKYBLUE (-1100 2700);
FORCEPROP 1 LAST MATERIAL X6S
J 0
(-1100 2800);
DISPLAY 0.617021 (-1100 2800);
PAINT SKYBLUE (-1100 2800);
FORCEPROP 1 LAST VOLTAGE 16V
J 0
(-1100 2900);
DISPLAY 0.617021 (-1100 2900);
PAINT SKYBLUE (-1100 2900);
FORCEPROP 1 LAST TOLERANCE 10%
J 0
(-1100 2850);
DISPLAY 0.617021 (-1100 2850);
PAINT SKYBLUE (-1100 2850);
FORCEPROP 1 LAST VALUE 1.0UF
J 0
(-1100 2950);
DISPLAY 0.617021 (-1100 2950);
PAINT SKYBLUE (-1100 2950);
FORCEPROP 0 LAST ROOM PROC_SIDEBAND
J 0
(-1100 3100);
DISPLAY 1.021277 (-1100 3100);
PAINT ORANGE (-1100 3100);
DISPLAY INVISIBLE (-1100 3100);
FORCEPROP 0 LAST BOM_COST PROC
J 0
(-1100 3100);
DISPLAY 1.021277 (-1100 3100);
PAINT ORANGE (-1100 3100);
DISPLAY INVISIBLE (-1100 3100);
FORCEPROP 1 LAST PATH I97
J 0
(-1100 3050);
DISPLAY 0.978723 (-1100 3050);
PAINT WHITE (-1100 3050);
DISPLAY INVISIBLE (-1100 3050);
FORCEPROP 2 LAST CDS_LIB mstr_discrete
J 0
(-1150 2900);
PAINT MONO (-1150 2900);
DISPLAY INVISIBLE (-1150 2900);
FORCEPROP 1 LASTPIN (-1150 2800) $PN 2
J 0
(-1140 2780);
DISPLAY 0.787234 (-1140 2780);
PAINT ORANGE (-1140 2780);
DISPLAY INVISIBLE (-1140 2780);
FORCEPROP 1 LASTPIN (-1150 3000) $PN 1
J 0
(-1140 2980);
DISPLAY 0.787234 (-1140 2980);
PAINT ORANGE (-1140 2980);
DISPLAY INVISIBLE (-1140 2980);
FORCEADD CAP..1
(-900 2900);
FORCEPROP 1 LAST PART_NUMBER D97712-011
J 0
(-850 2750);
DISPLAY 0.617021 (-850 2750);
PAINT BLUE (-850 2750);
FORCEPROP 1 LAST VOLTAGE 16V
J 0
(-850 2900);
DISPLAY 0.617021 (-850 2900);
PAINT SKYBLUE (-850 2900);
FORCEPROP 1 LAST VALUE 1.0UF
J 0
(-850 2950);
DISPLAY 0.617021 (-850 2950);
PAINT SKYBLUE (-850 2950);
FORCEPROP 1 LAST LOCATION C25W42
J 0
(-850 3000);
DISPLAY 0.617021 (-850 3000);
PAINT AQUA (-850 3000);
FORCEPROP 1 LAST PACK_TYPE 0402
J 0
(-850 2700);
DISPLAY 0.617021 (-850 2700);
PAINT SKYBLUE (-850 2700);
FORCEPROP 1 LAST MATERIAL X6S
J 0
(-850 2800);
DISPLAY 0.617021 (-850 2800);
PAINT SKYBLUE (-850 2800);
FORCEPROP 1 LAST TOLERANCE 10%
J 0
(-850 2850);
DISPLAY 0.617021 (-850 2850);
PAINT SKYBLUE (-850 2850);
FORCEPROP 0 LAST ROOM PROC_SIDEBAND
J 0
(-850 3100);
DISPLAY 1.021277 (-850 3100);
PAINT ORANGE (-850 3100);
DISPLAY INVISIBLE (-850 3100);
FORCEPROP 0 LAST BOM_COST PROC
J 0
(-850 3100);
DISPLAY 1.021277 (-850 3100);
PAINT ORANGE (-850 3100);
DISPLAY INVISIBLE (-850 3100);
FORCEPROP 1 LAST PATH I98
J 0
(-850 3050);
DISPLAY 0.978723 (-850 3050);
PAINT WHITE (-850 3050);
DISPLAY INVISIBLE (-850 3050);
FORCEPROP 2 LAST CDS_LIB mstr_discrete
J 0
(-900 2900);
PAINT MONO (-900 2900);
DISPLAY INVISIBLE (-900 2900);
FORCEPROP 1 LASTPIN (-900 2800) $PN 2
J 0
(-890 2780);
DISPLAY 0.787234 (-890 2780);
PAINT ORANGE (-890 2780);
DISPLAY INVISIBLE (-890 2780);
FORCEPROP 1 LASTPIN (-900 3000) $PN 1
J 0
(-890 2980);
DISPLAY 0.787234 (-890 2980);
PAINT ORANGE (-890 2980);
DISPLAY INVISIBLE (-890 2980);
FORCEADD CAP..1
(-1025 4100);
FORCEPROP 1 LAST TOLERANCE 10%
J 0
(-975 4050);
DISPLAY 0.617021 (-975 4050);
PAINT SKYBLUE (-975 4050);
FORCEPROP 1 LAST LOCATION C25W32
J 0
(-975 4200);
DISPLAY 0.617021 (-975 4200);
PAINT AQUA (-975 4200);
FORCEPROP 1 LAST PACK_TYPE 0402
J 0
(-975 3900);
DISPLAY 0.617021 (-975 3900);
PAINT SKYBLUE (-975 3900);
FORCEPROP 1 LAST PART_NUMBER D97712-011
J 0
(-975 3950);
DISPLAY 0.617021 (-975 3950);
PAINT BLUE (-975 3950);
FORCEPROP 1 LAST MATERIAL X6S
J 0
(-975 4000);
DISPLAY 0.617021 (-975 4000);
PAINT SKYBLUE (-975 4000);
FORCEPROP 1 LAST VALUE 1.0UF
J 0
(-975 4150);
DISPLAY 0.617021 (-975 4150);
PAINT SKYBLUE (-975 4150);
FORCEPROP 1 LAST VOLTAGE 16V
J 0
(-975 4100);
DISPLAY 0.617021 (-975 4100);
PAINT SKYBLUE (-975 4100);
FORCEPROP 0 LAST BOM_COST PROC
J 0
(-975 4300);
DISPLAY 1.021277 (-975 4300);
PAINT ORANGE (-975 4300);
DISPLAY INVISIBLE (-975 4300);
FORCEPROP 0 LAST ROOM PROC_SIDEBAND
J 0
(-975 4300);
DISPLAY 1.021277 (-975 4300);
PAINT ORANGE (-975 4300);
DISPLAY INVISIBLE (-975 4300);
FORCEPROP 1 LAST PATH I99
J 0
(-975 4250);
DISPLAY 0.978723 (-975 4250);
PAINT WHITE (-975 4250);
DISPLAY INVISIBLE (-975 4250);
FORCEPROP 2 LAST CDS_LIB mstr_discrete
J 0
(-1025 4100);
PAINT MONO (-1025 4100);
DISPLAY INVISIBLE (-1025 4100);
FORCEPROP 1 LASTPIN (-1025 4000) $PN 2
J 0
(-1015 3980);
DISPLAY 0.787234 (-1015 3980);
PAINT ORANGE (-1015 3980);
DISPLAY INVISIBLE (-1015 3980);
FORCEPROP 1 LASTPIN (-1025 4200) $PN 1
J 0
(-1015 4180);
DISPLAY 0.787234 (-1015 4180);
PAINT ORANGE (-1015 4180);
DISPLAY INVISIBLE (-1015 4180);
FORCEADD INTEL_CORP_BPAGE..1
(5375 1000);
FORCEPROP 1 LAST CDS_CON_LAST_MODIFIED Fri Jun 16 17:48:56 2017
J 0
(3950 1325);
DISPLAY 1.361702 (3950 1325);
PAINT GREEN (3950 1325);
DISPLAY INVISIBLE (3950 1325);
FORCEPROP 2 LAST CUSTOM_TXT_CDS <XR_PAGE_TITLE>
J 0
(-2515 6250);
DISPLAY 0.638298 (-2515 6250);
PAINT PINK (-2515 6250);
DISPLAY INVISIBLE (-2515 6250);
FORCEPROP 2 LAST CUSTOM_TXT_CDS <CON_LAST_MODIFIED>
J 0
(1350 1100);
PAINT ORANGE (1350 1100);
FORCEPROP 2 LAST CUSTOM_TXT_CDS <CURRENT_DESIGN_SHEET> OF <TOTAL_DESIGN_SHEETS>
J 0
(4875 1025);
PAINT ORANGE (4875 1025);
FORCEPROP 1 LAST SCH_TITLE BMC DECOUPLING CAPS
J 0
(-2575 1050);
DISPLAY 1.212766 (-2575 1050);
PAINT ORANGE (-2575 1050);
FORCEPROP 2 LAST PAGE_BORDER TRUE
J 0
(-2515 6250);
DISPLAY 0.851064 (-2515 6250);
PAINT PINK (-2515 6250);
DISPLAY INVISIBLE (-2515 6250);
FORCEPROP 2 LAST CDS_LIB mstr_symbols
J 0
(5375 1000);
DISPLAY 1.361702 (5375 1000);
PAINT ORANGE (5375 1000);
DISPLAY INVISIBLE (5375 1000);
FORCEPROP 1 LAST COMMENT_BODY TRUE
J 0
(5387 1012);
DISPLAY 0.617021 (5387 1012);
PAINT GREEN (5387 1012);
DISPLAY INVISIBLE (5387 1012);
FORCEPROP 2 LAST CDS_XR_PAGE_TITLE CR-149 : @BASEBOARD_FAB2_LIB.BASEBOARD_FAB2(SCH_1):PAGE149
J 0
(-2515 6250);
DISPLAY 0.638298 (-2515 6250);
PAINT PINK (-2515 6250);
DISPLAY INVISIBLE (-2515 6250);
WIRE 16 -1 (3800 5500)(3800 5600);
WIRE 16 -1 (4000 5500)(3800 5500);
WIRE 16 -1 (3100 5650)(3100 5500);
WIRE 16 -1 (3100 5500)(2700 5500);
WIRE 16 -1 (3100 5500)(3100 5275);
WIRE 16 -1 (2700 5500)(2400 5500);
WIRE 16 -1 (2700 5275)(2700 5500);
WIRE 16 -1 (2400 5500)(2150 5500);
WIRE 16 -1 (2400 5275)(2400 5500);
WIRE 16 -1 (1650 5500)(2150 5500);
WIRE 16 -1 (2150 5500)(2150 5275);
WIRE 16 -1 (3100 4750)(3100 4850);
WIRE 16 -1 (2700 4850)(3100 4850);
WIRE 16 -1 (3100 4850)(3100 5075);
WIRE 16 -1 (2400 4850)(2700 4850);
WIRE 16 -1 (2700 5075)(2700 4850);
WIRE 16 -1 (2150 4850)(2400 4850);
WIRE 16 -1 (2400 5075)(2400 4850);
WIRE 16 -1 (2150 5075)(2150 4850);
WIRE 16 -1 (4800 5600)(4800 5500);
WIRE 16 -1 (4300 5500)(4800 5500);
WIRE 16 -1 (4800 5400)(4800 5500);
WIRE 16 -1 (4200 5500)(4300 5500);
WIRE 16 -1 (4300 5400)(4300 5500);
WIRE 16 -1 (1200 5600)(1200 5500);
WIRE 16 -1 (1200 5500)(1350 5500);
WIRE 16 -1 (550 5150)(550 5125);
WIRE 16 -1 (150 5150)(550 5150);
WIRE 16 -1 (550 5150)(550 5300);
WIRE 16 -1 (-250 5150)(150 5150);
WIRE 16 -1 (150 5300)(150 5150);
WIRE 16 -1 (-650 5150)(-250 5150);
WIRE 16 -1 (-250 5300)(-250 5150);
WIRE 16 -1 (-1050 5150)(-650 5150);
WIRE 16 -1 (-650 5300)(-650 5150);
WIRE 16 -1 (-1450 5150)(-1050 5150);
WIRE 16 -1 (-1050 5300)(-1050 5150);
WIRE 16 -1 (-1850 5150)(-1450 5150);
WIRE 16 -1 (-1450 5300)(-1450 5150);
WIRE 16 -1 (-2250 5150)(-1850 5150);
WIRE 16 -1 (-1850 5300)(-1850 5150);
WIRE 16 -1 (-2250 5300)(-2250 5150);
WIRE 16 -1 (3725 4450)(3725 4300);
WIRE 16 -1 (3725 4300)(3325 4300);
WIRE 16 -1 (3725 4300)(3725 4075);
WIRE 16 -1 (3325 4300)(2775 4300);
WIRE 16 -1 (3325 4075)(3325 4300);
WIRE 16 -1 (2475 4300)(2775 4300);
WIRE 16 -1 (2775 4300)(2775 4075);
WIRE 16 -1 (3725 3650)(3725 3875);
WIRE 16 -1 (3325 3650)(3725 3650);
WIRE 16 -1 (3325 3650)(2775 3650);
WIRE 16 -1 (3325 3875)(3325 3650);
WIRE 16 -1 (2775 3875)(2775 3650);
WIRE 16 -1 (3950 3100)(3950 3350);
WIRE 16 -1 (3950 3100)(4250 3100);
WIRE 16 -1 (3950 3000)(3950 3100);
WIRE 16 -1 (4250 3100)(4500 3100);
WIRE 16 -1 (4250 3000)(4250 3100);
WIRE 16 -1 (4500 3100)(4750 3100);
WIRE 16 -1 (4500 3000)(4500 3100);
WIRE 16 -1 (4750 3100)(5000 3100);
WIRE 16 -1 (4750 3000)(4750 3100);
WIRE 16 -1 (5000 3100)(5000 3025);
WIRE 16 -1 (3275 2675)(3275 2900);
WIRE 16 -1 (2875 2675)(3275 2675);
WIRE 16 -1 (2875 2675)(2325 2675);
WIRE 16 -1 (2875 2900)(2875 2675);
WIRE 16 -1 (2325 2900)(2325 2675);
WIRE 16 -1 (4800 5000)(4800 4950);
WIRE 16 -1 (4300 5000)(4800 5000);
WIRE 16 -1 (4800 5200)(4800 5000);
WIRE 16 -1 (4300 5200)(4300 5000);
WIRE 16 -1 (2425 1425)(2425 1650);
WIRE 16 -1 (2025 1425)(2425 1425);
WIRE 16 -1 (2025 1425)(1475 1425);
WIRE 16 -1 (2025 1650)(2025 1425);
WIRE 16 -1 (1475 1625)(1475 1425);
WIRE 16 -1 (2025 4400)(2025 4300);
WIRE 16 -1 (2025 4300)(2175 4300);
WIRE 16 -1 (1575 3425)(1575 3325);
WIRE 16 -1 (2325 3325)(1575 3325);
WIRE 16 -1 (2875 3325)(2325 3325);
WIRE 16 -1 (2325 3325)(2325 3100);
WIRE 16 -1 (3275 3325)(2875 3325);
WIRE 16 -1 (2875 3100)(2875 3325);
WIRE 16 -1 (3275 3325)(3275 3100);
WIRE 16 -1 (1125 4450)(1125 4275);
WIRE 16 -1 (775 4275)(1125 4275);
WIRE 16 -1 (1125 4100)(1125 4275);
WIRE 16 -1 (425 4275)(775 4275);
WIRE 16 -1 (775 4100)(775 4275);
WIRE 16 -1 (225 4275)(425 4275);
WIRE 16 -1 (425 4100)(425 4275);
WIRE 16 -1 (1125 3675)(1125 3525);
WIRE 16 -1 (775 3675)(1125 3675);
WIRE 16 -1 (1125 3675)(1125 3900);
WIRE 16 -1 (775 3675)(425 3675);
WIRE 16 -1 (775 3900)(775 3675);
WIRE 16 -1 (425 3900)(425 3675);
WIRE 16 -1 (725 2175)(725 2075);
WIRE 16 -1 (1475 2075)(725 2075);
WIRE 16 -1 (2025 2075)(1475 2075);
WIRE 16 -1 (1475 2075)(1475 1825);
WIRE 16 -1 (2425 2075)(2025 2075);
WIRE 16 -1 (2025 1850)(2025 2075);
WIRE 16 -1 (2425 2075)(2425 1850);
WIRE 16 -1 (475 2450)(475 2600);
WIRE 16 -1 (475 2600)(250 2600);
WIRE 16 -1 (475 2600)(550 2600);
WIRE 16 -1 (550 2600)(550 2800);
WIRE 16 -1 (250 2600)(-100 2600);
WIRE 16 -1 (250 2800)(250 2600);
WIRE 16 -1 (-100 2600)(-350 2600);
WIRE 16 -1 (-100 2800)(-100 2600);
WIRE 16 -1 (-350 2600)(-650 2600);
WIRE 16 -1 (-350 2800)(-350 2600);
WIRE 16 -1 (-900 2600)(-650 2600);
WIRE 16 -1 (-650 2600)(-650 2800);
WIRE 16 -1 (-1150 2600)(-900 2600);
WIRE 16 -1 (-900 2800)(-900 2600);
WIRE 16 -1 (-1450 2600)(-1150 2600);
WIRE 16 -1 (-1150 2800)(-1150 2600);
WIRE 16 -1 (-1450 2800)(-1450 2600);
WIRE 16 -1 (-2250 5575)(-2250 5625);
WIRE 16 -1 (-2250 5575)(-1850 5575);
WIRE 16 -1 (-2250 5500)(-2250 5575);
WIRE 16 -1 (-1850 5575)(-1450 5575);
WIRE 16 -1 (-1850 5575)(-1850 5500);
WIRE 16 -1 (-1450 5575)(-1050 5575);
WIRE 16 -1 (-1450 5575)(-1450 5500);
WIRE 16 -1 (-1050 5575)(-650 5575);
WIRE 16 -1 (-1050 5575)(-1050 5500);
WIRE 16 -1 (-650 5575)(-250 5575);
WIRE 16 -1 (-650 5575)(-650 5500);
WIRE 16 -1 (-250 5575)(150 5575);
WIRE 16 -1 (-250 5575)(-250 5500);
WIRE 16 -1 (150 5575)(550 5575);
WIRE 16 -1 (150 5575)(150 5500);
WIRE 16 -1 (550 5575)(550 5500);
WIRE 16 -1 (-175 4275)(-175 4375);
WIRE 16 -1 (25 4275)(-175 4275);
WIRE 16 -1 (-675 4475)(-675 4400);
WIRE 16 -1 (-1025 4400)(-675 4400);
WIRE 16 -1 (-675 4400)(-675 4200);
WIRE 16 -1 (-1025 4400)(-1475 4400);
WIRE 16 -1 (-1025 4200)(-1025 4400);
WIRE 16 -1 (-1925 4400)(-1475 4400);
WIRE 16 -1 (-1475 4225)(-1475 4400);
WIRE 16 -1 (-675 3800)(-675 3650);
WIRE 16 -1 (-1025 3800)(-675 3800);
WIRE 16 -1 (-675 3800)(-675 4000);
WIRE 16 -1 (-1025 3800)(-1475 3800);
WIRE 16 -1 (-1025 4000)(-1025 3800);
WIRE 16 -1 (-1475 4025)(-1475 3800);
WIRE 16 -1 (-100 3350)(-100 3200);
WIRE 16 -1 (-350 3200)(-100 3200);
WIRE 16 -1 (-100 3200)(250 3200);
WIRE 16 -1 (-100 3000)(-100 3200);
WIRE 16 -1 (250 3200)(550 3200);
WIRE 16 -1 (250 3000)(250 3200);
WIRE 16 -1 (-650 3200)(-350 3200);
WIRE 16 -1 (-350 3000)(-350 3200);
WIRE 16 -1 (-900 3200)(-650 3200);
WIRE 16 -1 (-650 3000)(-650 3200);
WIRE 16 -1 (550 3200)(550 3000);
WIRE 16 -1 (-1150 3200)(-900 3200);
WIRE 16 -1 (-900 3000)(-900 3200);
WIRE 16 -1 (-1450 3200)(-1150 3200);
WIRE 16 -1 (-1150 3000)(-1150 3200);
WIRE 16 -1 (-1900 3200)(-1450 3200);
WIRE 16 -1 (-1450 3000)(-1450 3200);
WIRE 16 -1 (5000 2600)(5000 2650);
WIRE 16 -1 (4750 2650)(5000 2650);
WIRE 16 -1 (5000 2825)(5000 2650);
WIRE 16 -1 (4500 2650)(4750 2650);
WIRE 16 -1 (4750 2800)(4750 2650);
WIRE 16 -1 (4250 2650)(4500 2650);
WIRE 16 -1 (4500 2800)(4500 2650);
WIRE 16 -1 (3950 2650)(4250 2650);
WIRE 16 -1 (4250 2800)(4250 2650);
WIRE 16 -1 (3950 2800)(3950 2650);
WIRE 16 -1 (-550 2300)(-550 2150);
WIRE 16 -1 (-550 2150)(-850 2150);
WIRE 16 -1 (-550 2150)(-550 1950);
WIRE 16 -1 (-850 2150)(-1150 2150);
WIRE 16 -1 (-850 2150)(-850 1950);
WIRE 16 -1 (-1150 2150)(-1450 2150);
WIRE 16 -1 (-1150 1950)(-1150 2150);
WIRE 16 -1 (-1875 2150)(-1450 2150);
WIRE 16 -1 (-1450 1925)(-1450 2150);
WIRE 16 -1 (-550 1475)(-550 1500);
WIRE 16 -1 (-550 1500)(-850 1500);
WIRE 16 -1 (-550 1500)(-550 1750);
WIRE 16 -1 (-850 1500)(-1150 1500);
WIRE 16 -1 (-850 1750)(-850 1500);
WIRE 16 -1 (-1150 1500)(-1450 1500);
WIRE 16 -1 (-1150 1750)(-1150 1500);
WIRE 16 -1 (-1450 1725)(-1450 1500);
WIRE 16 -1 (-2350 4500)(-2350 4400);
WIRE 16 -1 (-2350 4400)(-2225 4400);
WIRE 16 -1 (-2325 3300)(-2325 3200);
WIRE 16 -1 (-2325 3200)(-2200 3200);
WIRE 16 -1 (-2325 2250)(-2325 2150);
WIRE 16 -1 (-2325 2150)(-2175 2150);
WIRE 16 2175 (-2375 5050)(-475 5050);
WIRE 16 2175 (-475 5050)(-475 5600);
WIRE 16 2175 (-2375 5050)(-2375 5600);
WIRE 16 2175 (-2375 5600)(-475 5600);
WIRE 3 682 (2850 2500)(2850 1450);
WIRE 3 682 (5200 2500)(2850 2500);
WIRE 3 682 (2850 1450)(5200 1450);
WIRE 3 682 (5200 1450)(5200 2500);
WIRE 3 682 (-1550 1400)(-250 1400);
WIRE 3 682 (-1550 2200)(-1550 1400);
WIRE 3 682 (-250 1400)(-250 2200);
WIRE 3 682 (-250 2200)(-1550 2200);
WIRE 16 2175 (-1550 3250)(-250 3250);
WIRE 16 2175 (-250 2500)(-250 3250);
WIRE 16 2175 (-1550 2500)(-1550 3250);
WIRE 16 2175 (-1550 2500)(-250 2500);
WIRE 16 2175 (-150 3250)(925 3250);
WIRE 16 2175 (925 2525)(925 3250);
WIRE 16 2175 (-150 2525)(-150 3250);
WIRE 16 2175 (-150 2525)(925 2525);
WIRE 16 2175 (-350 5600)(900 5600);
WIRE 16 2175 (900 5050)(900 5600);
WIRE 16 2175 (-350 5050)(-350 5600);
WIRE 16 2175 (-350 5050)(900 5050);
WIRE 3 682 (50 5650)(50 5000);
WIRE 3 682 (450 5650)(50 5650);
WIRE 3 682 (50 5000)(450 5000);
WIRE 3 682 (450 5000)(450 5650);
DOT 1 (550 5150);
DOT 1 (150 5150);
DOT 1 (-250 5150);
DOT 1 (-650 5150);
DOT 1 (-1050 5150);
DOT 1 (-1850 5150);
DOT 1 (-1450 5150);
DOT 1 (150 5575);
DOT 1 (-250 5575);
DOT 1 (2400 5500);
DOT 1 (-675 3800);
DOT 1 (1125 3675);
DOT 1 (-1850 5575);
DOT 1 (250 3200);
DOT 1 (-100 3200);
DOT 1 (-650 3200);
DOT 1 (4500 3100);
DOT 1 (4500 2650);
DOT 1 (-1450 3200);
DOT 1 (-1150 3200);
DOT 1 (-1025 3800);
DOT 1 (-900 2600);
DOT 1 (-350 2600);
DOT 1 (-100 2600);
DOT 1 (-350 3200);
DOT 1 (-2250 5575);
DOT 1 (-1025 4400);
DOT 1 (-1050 5575);
DOT 1 (-1450 5575);
DOT 1 (-650 5575);
DOT 1 (2025 1425);
DOT 1 (250 2600);
DOT 1 (475 2600);
DOT 1 (775 3675);
DOT 1 (2025 2075);
DOT 1 (1475 2075);
DOT 1 (2875 2675);
DOT 1 (2325 3325);
DOT 1 (2875 3325);
DOT 1 (3325 3650);
DOT 1 (775 4275);
DOT 1 (1125 4275);
DOT 1 (2400 4850);
DOT 1 (2700 4850);
DOT 1 (2150 5500);
DOT 1 (2700 5500);
DOT 1 (3100 5500);
DOT 1 (3100 4850);
DOT 1 (3325 4300);
DOT 1 (3725 4300);
DOT 1 (4250 2650);
DOT 1 (4750 2650);
DOT 1 (5000 2650);
DOT 1 (4250 3100);
DOT 1 (4800 5000);
DOT 1 (4300 5500);
DOT 1 (4800 5500);
DOT 1 (4750 3100);
DOT 1 (2775 4300);
DOT 1 (-650 2600);
DOT 1 (-675 4400);
DOT 1 (425 4275);
DOT 1 (-900 3200);
DOT 1 (3950 3100);
DOT 1 (-1475 4400);
DOT 1 (-1150 2600);
DOT 1 (-550 2150);
DOT 1 (-550 1500);
DOT 1 (-1450 2150);
DOT 1 (-1150 2150);
DOT 1 (-1150 1500);
DOT 1 (-850 2150);
DOT 1 (-850 1500);
FORCENOTE
80 OHM@100MHZ 3A
(1950 4000) 0;
DISPLAY LEFT (1950 4000);
DISPLAY 1.021277 (1950 4000);
PAINT PURPLE (1950 4000);
FORCENOTE
PLACEMENT CLOSE K5,K6 PIN  OR  POWER  PLANE
(-25 4625) 0;
DISPLAY LEFT (-25 4625);
DISPLAY 1.021277 (-25 4625);
PAINT PURPLE (-25 4625);
FORCENOTE
1UF 6.3V NEED CHANGE TO 16V WAIT FOR SYMBOL
(75 5875) 0;
DISPLAY LEFT (75 5875);
DISPLAY 1.702128 (75 5875);
PAINT RED (75 5875);
FORCENOTE
PLACEMENT CLOSE CHIP
(-125 5725) 0;
DISPLAY LEFT (-125 5725);
DISPLAY 1.021277 (-125 5725);
PAINT PURPLE (-125 5725);
FORCENOTE
PLACEMENT CLOSE CHIP
(100 3325) 0;
DISPLAY LEFT (100 3325);
DISPLAY 1.021277 (100 3325);
PAINT PURPLE (100 3325);
FORCENOTE
PLACEMENT CLOSE L5,L6 PIN OR POWER PLANE
(2375 4425) 0;
DISPLAY LEFT (2375 4425);
DISPLAY 1.021277 (2375 4425);
PAINT PURPLE (2375 4425);
FORCENOTE
PLACEMENT CLOSE J7,H7 PIN OR POWER PLANE
(1600 5575) 0;
DISPLAY LEFT (1600 5575);
DISPLAY 1.021277 (1600 5575);
PAINT PURPLE (1600 5575);
FORCENOTE
ROOM=SM_CONTROLLER
(-2383 1323) 0;
DISPLAY LEFT (-2383 1323);
DISPLAY 0.617021 (-2383 1323);
PAINT PURPLE (-2383 1323);
FORCENOTE
80 OHM@100MHZ 3A
(-2350 4100) 0;
DISPLAY LEFT (-2350 4100);
DISPLAY 1.021277 (-2350 4100);
PAINT PURPLE (-2350 4100);
FORCENOTE
80 OHM@100MHZ 3A
(-2325 2900) 0;
DISPLAY LEFT (-2325 2900);
DISPLAY 1.021277 (-2325 2900);
PAINT PURPLE (-2325 2900);
FORCENOTE
80 OHM@100MHZ 3A
(1200 5200) 0;
DISPLAY LEFT (1200 5200);
DISPLAY 1.021277 (1200 5200);
PAINT PURPLE (1200 5200);
FORCENOTE
PLACEMENT CLOSE T8,10,12,13,14 PIN OR POWER PLANE
(3300 3250) 0;
DISPLAY LEFT (3300 3250);
DISPLAY 1.021277 (3300 3250);
PAINT PURPLE (3300 3250);
FORCENOTE
TP FAB3 DELETE FB2T6, C25W63, C25W64, C25W65 0922
(2850 1400) 0;
DISPLAY LEFT (2850 1400);
DISPLAY 0.638298 (2850 1400);
PAINT RED (2850 1400);
FORCENOTE
PLACEMENT CLOSE F10,F11,F7,F8 PIN OR POWER PLANE
(850 2125) 0;
DISPLAY LEFT (850 2125);
DISPLAY 1.021277 (850 2125);
PAINT PURPLE (850 2125);
FORCENOTE
PLACEMENT CLOSE J6  PIN  OR  POWER  PLANE
(-1775 4425) 0;
DISPLAY LEFT (-1775 4425);
DISPLAY 1.021277 (-1775 4425);
PAINT PURPLE (-1775 4425);
FORCENOTE
PLACEMENT CLOSE K17,F13,F12 PIN  OR  POWER  PLANE
(-1825 3300) 0;
DISPLAY LEFT (-1825 3300);
DISPLAY 1.021277 (-1825 3300);
PAINT PURPLE (-1825 3300);
FORCENOTE
TP FAB3 CHANGE C25W57 FROM 1UF TO 100PF; NOPOP C25W59 0922
(-1550 1350) 0;
DISPLAY LEFT (-1550 1350);
DISPLAY 0.638298 (-1550 1350);
PAINT RED (-1550 1350);
FORCENOTE
80 OHM@100MHZ 3A
(-2325 1850) 0;
DISPLAY LEFT (-2325 1850);
DISPLAY 1.021277 (-2325 1850);
PAINT PURPLE (-2325 1850);
FORCENOTE
PLACEMENT CLOSE Y17,W17 PIN OR POWER PLANE
(-1850 2225) 0;
DISPLAY LEFT (-1850 2225);
DISPLAY 1.021277 (-1850 2225);
PAINT PURPLE (-1850 2225);
FORCENOTE
PLACEMENT CLOSE F6,AA17,G13 AND 1VDD PIN CHIP OR POWER PLANE
(-2200 5625) 0;
DISPLAY LEFT (-2200 5625);
DISPLAY 1.021277 (-2200 5625);
PAINT PURPLE (-2200 5625);
FORCENOTE
PLACEMENT CLOSE J17,K17 PIN OR POWER PLANE
(1875 3400) 0;
DISPLAY LEFT (1875 3400);
DISPLAY 1.021277 (1875 3400);
PAINT PURPLE (1875 3400);
FORCENOTE
TP FAB3 CHANGE CAP FROM 0805 TO 0603 0922
(50 4950) 0;
DISPLAY LEFT (50 4950);
DISPLAY 0.638298 (50 4950);
PAINT RED (50 4950);
QUIT
